FILE_TYPE = MACRO_DRAWING;
SET COLOR_WIRE YELLOW;
SET COLOR_PROP MONO;
SET COLOR_DOT WHITE;
SET COLOR_ARC YELLOW;
SET COLOR_BODY GREEN;
SET COLOR_NOTE MONO;
SET PROP_DISPLAY VALUE;
SET PAGE_NUMBER P58;
FORCEADD OFFPAGE..5
(-6450 525);
FORCEPROP 2 LAST $XR1 80 
J 0
(-6764 525);
DISPLAY 0.638298 (-6764 525);
PAINT MONO (-6764 525);
FORCEPROP 2 LAST $XR0 79 
J 0
(-6674 525);
DISPLAY 0.638298 (-6674 525);
PAINT MONO (-6674 525);
FORCEPROP 2 LAST CDS_LIB mstr_standard
J 0
(-6450 525);
PAINT MONO (-6450 525);
DISPLAY INVISIBLE (-6450 525);
FORCEPROP 1 LAST OFFPAGE TRUE
J 0
(-6125 400);
DISPLAY 1.170213 (-6125 400);
PAINT GREEN (-6125 400);
DISPLAY INVISIBLE (-6125 400);
FORCEPROP 1 LAST COMMENT_BODY TRUE
J 0
(-6350 450);
DISPLAY 1.170213 (-6350 450);
PAINT GREEN (-6350 450);
DISPLAY INVISIBLE (-6350 450);
FORCEPROP 2 LAST PATH I1
J 0
(-6400 600);
DISPLAY 1.021277 (-6400 600);
PAINT ORANGE (-6400 600);
DISPLAY INVISIBLE (-6400 600);
FORCEADD TAP..6
(-5600 825);
FORCEPROP 3 LASTPIN (-5550 825) SIG_NAME M_H_CLK_DP<0>
J 0
(-5540 835);
DISPLAY 0.659574 (-5540 835);
PAINT MONO (-5540 835);
DISPLAY INVISIBLE (-5540 835);
FORCEPROP 1 LASTPIN (-5550 825) BN 0
J 0
(-5602 833);
DISPLAY 0.617021 (-5602 833);
PAINT GREEN (-5602 833);
FORCEPROP 2 LAST CDS_LIB mstr_standard
J 0
(-5600 825);
PAINT MONO (-5600 825);
DISPLAY INVISIBLE (-5600 825);
FORCEPROP 1 LAST BODY_TYPE PLUMBING
J 0
(-5600 775);
DISPLAY 1.595745 (-5600 775);
PAINT GREEN (-5600 775);
DISPLAY INVISIBLE (-5600 775);
FORCEPROP 1 LAST HDL_TAP TRUE
J 0
(-5275 700);
DISPLAY 1.595745 (-5275 700);
PAINT GREEN (-5275 700);
DISPLAY INVISIBLE (-5275 700);
FORCEPROP 1 LAST PATH I10
J 0
(-5602 825);
DISPLAY 0.872340 (-5602 825);
PAINT GREEN (-5602 825);
DISPLAY INVISIBLE (-5602 825);
FORCEADD TAP..6
R 2
(-2875 1575);
FORCEPROP 3 LASTPIN (-2925 1575) SIG_NAME M_H_ODT<3>
J 0
(-2915 1585);
DISPLAY 0.659574 (-2915 1585);
PAINT MONO (-2915 1585);
DISPLAY INVISIBLE (-2915 1585);
FORCEPROP 1 LASTPIN (-2925 1575) BN 3
J 2
(-2873 1583);
DISPLAY 0.617021 (-2873 1583);
PAINT GREEN (-2873 1583);
FORCEPROP 2 LAST CDS_LIB mstr_standard
J 0
(-2875 1575);
PAINT MONO (-2875 1575);
DISPLAY INVISIBLE (-2875 1575);
FORCEPROP 1 LAST BODY_TYPE PLUMBING
J 2
(-2875 1525);
DISPLAY 1.595745 (-2875 1525);
PAINT GREEN (-2875 1525);
DISPLAY INVISIBLE (-2875 1525);
FORCEPROP 1 LAST HDL_TAP TRUE
J 2
(-3200 1450);
DISPLAY 1.595745 (-3200 1450);
PAINT GREEN (-3200 1450);
DISPLAY INVISIBLE (-3200 1450);
FORCEPROP 1 LAST PATH I100
J 2
(-2873 1575);
DISPLAY 0.872340 (-2873 1575);
PAINT GREEN (-2873 1575);
DISPLAY INVISIBLE (-2873 1575);
FORCEADD TAP..6
R 2
(-2875 1525);
FORCEPROP 3 LASTPIN (-2925 1525) SIG_NAME M_H_ODT<2>
J 0
(-2915 1535);
DISPLAY 0.659574 (-2915 1535);
PAINT MONO (-2915 1535);
DISPLAY INVISIBLE (-2915 1535);
FORCEPROP 1 LASTPIN (-2925 1525) BN 2
J 2
(-2873 1533);
DISPLAY 0.617021 (-2873 1533);
PAINT GREEN (-2873 1533);
FORCEPROP 2 LAST CDS_LIB mstr_standard
J 0
(-2875 1525);
PAINT MONO (-2875 1525);
DISPLAY INVISIBLE (-2875 1525);
FORCEPROP 1 LAST BODY_TYPE PLUMBING
J 2
(-2875 1475);
DISPLAY 1.595745 (-2875 1475);
PAINT GREEN (-2875 1475);
DISPLAY INVISIBLE (-2875 1475);
FORCEPROP 1 LAST HDL_TAP TRUE
J 2
(-3200 1400);
DISPLAY 1.595745 (-3200 1400);
PAINT GREEN (-3200 1400);
DISPLAY INVISIBLE (-3200 1400);
FORCEPROP 1 LAST PATH I101
J 2
(-2873 1525);
DISPLAY 0.872340 (-2873 1525);
PAINT GREEN (-2873 1525);
DISPLAY INVISIBLE (-2873 1525);
FORCEADD TAP..6
R 2
(-2875 1475);
FORCEPROP 3 LASTPIN (-2925 1475) SIG_NAME M_H_ODT<1>
J 0
(-2915 1485);
DISPLAY 0.659574 (-2915 1485);
PAINT MONO (-2915 1485);
DISPLAY INVISIBLE (-2915 1485);
FORCEPROP 1 LASTPIN (-2925 1475) BN 1
J 2
(-2873 1483);
DISPLAY 0.617021 (-2873 1483);
PAINT GREEN (-2873 1483);
FORCEPROP 2 LAST CDS_LIB mstr_standard
J 0
(-2875 1475);
PAINT MONO (-2875 1475);
DISPLAY INVISIBLE (-2875 1475);
FORCEPROP 1 LAST BODY_TYPE PLUMBING
J 2
(-2875 1425);
DISPLAY 1.595745 (-2875 1425);
PAINT GREEN (-2875 1425);
DISPLAY INVISIBLE (-2875 1425);
FORCEPROP 1 LAST HDL_TAP TRUE
J 2
(-3200 1350);
DISPLAY 1.595745 (-3200 1350);
PAINT GREEN (-3200 1350);
DISPLAY INVISIBLE (-3200 1350);
FORCEPROP 1 LAST PATH I102
J 2
(-2873 1475);
DISPLAY 0.872340 (-2873 1475);
PAINT GREEN (-2873 1475);
DISPLAY INVISIBLE (-2873 1475);
FORCEADD TAP..6
R 2
(-2875 1675);
FORCEPROP 3 LASTPIN (-2925 1675) SIG_NAME M_H_CKE<0>
J 0
(-2915 1685);
DISPLAY 0.659574 (-2915 1685);
PAINT MONO (-2915 1685);
DISPLAY INVISIBLE (-2915 1685);
FORCEPROP 1 LASTPIN (-2925 1675) BN 0
J 2
(-2873 1683);
DISPLAY 0.617021 (-2873 1683);
PAINT GREEN (-2873 1683);
FORCEPROP 2 LAST CDS_LIB mstr_standard
J 0
(-2875 1675);
PAINT MONO (-2875 1675);
DISPLAY INVISIBLE (-2875 1675);
FORCEPROP 1 LAST BODY_TYPE PLUMBING
J 2
(-2875 1625);
DISPLAY 1.595745 (-2875 1625);
PAINT GREEN (-2875 1625);
DISPLAY INVISIBLE (-2875 1625);
FORCEPROP 1 LAST HDL_TAP TRUE
J 2
(-3200 1550);
DISPLAY 1.595745 (-3200 1550);
PAINT GREEN (-3200 1550);
DISPLAY INVISIBLE (-3200 1550);
FORCEPROP 1 LAST PATH I103
J 2
(-2873 1675);
DISPLAY 0.872340 (-2873 1675);
PAINT GREEN (-2873 1675);
DISPLAY INVISIBLE (-2873 1675);
FORCEADD TAP..6
R 2
(-2875 1725);
FORCEPROP 3 LASTPIN (-2925 1725) SIG_NAME M_H_CKE<1>
J 0
(-2915 1735);
DISPLAY 0.659574 (-2915 1735);
PAINT MONO (-2915 1735);
DISPLAY INVISIBLE (-2915 1735);
FORCEPROP 1 LASTPIN (-2925 1725) BN 1
J 2
(-2873 1733);
DISPLAY 0.617021 (-2873 1733);
PAINT GREEN (-2873 1733);
FORCEPROP 2 LAST CDS_LIB mstr_standard
J 0
(-2875 1725);
PAINT MONO (-2875 1725);
DISPLAY INVISIBLE (-2875 1725);
FORCEPROP 1 LAST BODY_TYPE PLUMBING
J 2
(-2875 1675);
DISPLAY 1.595745 (-2875 1675);
PAINT GREEN (-2875 1675);
DISPLAY INVISIBLE (-2875 1675);
FORCEPROP 1 LAST HDL_TAP TRUE
J 2
(-3200 1600);
DISPLAY 1.595745 (-3200 1600);
PAINT GREEN (-3200 1600);
DISPLAY INVISIBLE (-3200 1600);
FORCEPROP 1 LAST PATH I104
J 2
(-2873 1725);
DISPLAY 0.872340 (-2873 1725);
PAINT GREEN (-2873 1725);
DISPLAY INVISIBLE (-2873 1725);
FORCEADD TAP..6
R 2
(-2875 1775);
FORCEPROP 3 LASTPIN (-2925 1775) SIG_NAME M_H_CKE<2>
J 0
(-2915 1785);
DISPLAY 0.659574 (-2915 1785);
PAINT MONO (-2915 1785);
DISPLAY INVISIBLE (-2915 1785);
FORCEPROP 1 LASTPIN (-2925 1775) BN 2
J 2
(-2873 1783);
DISPLAY 0.617021 (-2873 1783);
PAINT GREEN (-2873 1783);
FORCEPROP 2 LAST CDS_LIB mstr_standard
J 0
(-2875 1775);
PAINT MONO (-2875 1775);
DISPLAY INVISIBLE (-2875 1775);
FORCEPROP 1 LAST BODY_TYPE PLUMBING
J 2
(-2875 1725);
DISPLAY 1.595745 (-2875 1725);
PAINT GREEN (-2875 1725);
DISPLAY INVISIBLE (-2875 1725);
FORCEPROP 1 LAST HDL_TAP TRUE
J 2
(-3200 1650);
DISPLAY 1.595745 (-3200 1650);
PAINT GREEN (-3200 1650);
DISPLAY INVISIBLE (-3200 1650);
FORCEPROP 1 LAST PATH I105
J 2
(-2873 1775);
DISPLAY 0.872340 (-2873 1775);
PAINT GREEN (-2873 1775);
DISPLAY INVISIBLE (-2873 1775);
FORCEADD TAP..6
R 2
(-2875 1825);
FORCEPROP 3 LASTPIN (-2925 1825) SIG_NAME M_H_CKE<3>
J 0
(-2915 1835);
DISPLAY 0.659574 (-2915 1835);
PAINT MONO (-2915 1835);
DISPLAY INVISIBLE (-2915 1835);
FORCEPROP 1 LASTPIN (-2925 1825) BN 3
J 2
(-2873 1833);
DISPLAY 0.617021 (-2873 1833);
PAINT GREEN (-2873 1833);
FORCEPROP 2 LAST CDS_LIB mstr_standard
J 0
(-2875 1825);
PAINT MONO (-2875 1825);
DISPLAY INVISIBLE (-2875 1825);
FORCEPROP 1 LAST BODY_TYPE PLUMBING
J 2
(-2875 1775);
DISPLAY 1.595745 (-2875 1775);
PAINT GREEN (-2875 1775);
DISPLAY INVISIBLE (-2875 1775);
FORCEPROP 1 LAST HDL_TAP TRUE
J 2
(-3200 1700);
DISPLAY 1.595745 (-3200 1700);
PAINT GREEN (-3200 1700);
DISPLAY INVISIBLE (-3200 1700);
FORCEPROP 1 LAST PATH I106
J 2
(-2873 1825);
DISPLAY 0.872340 (-2873 1825);
PAINT GREEN (-2873 1825);
DISPLAY INVISIBLE (-2873 1825);
FORCEADD TAP..6
R 2
(-2875 1925);
FORCEPROP 3 LASTPIN (-2925 1925) SIG_NAME M_H_MA<0>
J 0
(-2915 1935);
DISPLAY 0.659574 (-2915 1935);
PAINT MONO (-2915 1935);
DISPLAY INVISIBLE (-2915 1935);
FORCEPROP 1 LASTPIN (-2925 1925) BN 0
J 2
(-2873 1933);
DISPLAY 0.617021 (-2873 1933);
PAINT GREEN (-2873 1933);
FORCEPROP 2 LAST CDS_LIB mstr_standard
J 0
(-2875 1925);
PAINT MONO (-2875 1925);
DISPLAY INVISIBLE (-2875 1925);
FORCEPROP 1 LAST BODY_TYPE PLUMBING
J 2
(-2875 1875);
DISPLAY 1.595745 (-2875 1875);
PAINT GREEN (-2875 1875);
DISPLAY INVISIBLE (-2875 1875);
FORCEPROP 1 LAST HDL_TAP TRUE
J 2
(-3200 1800);
DISPLAY 1.595745 (-3200 1800);
PAINT GREEN (-3200 1800);
DISPLAY INVISIBLE (-3200 1800);
FORCEPROP 1 LAST PATH I107
J 2
(-2873 1925);
DISPLAY 0.872340 (-2873 1925);
PAINT GREEN (-2873 1925);
DISPLAY INVISIBLE (-2873 1925);
FORCEADD TAP..6
R 2
(-2875 1975);
FORCEPROP 3 LASTPIN (-2925 1975) SIG_NAME M_H_MA<1>
J 0
(-2915 1985);
DISPLAY 0.659574 (-2915 1985);
PAINT MONO (-2915 1985);
DISPLAY INVISIBLE (-2915 1985);
FORCEPROP 1 LASTPIN (-2925 1975) BN 1
J 2
(-2873 1983);
DISPLAY 0.617021 (-2873 1983);
PAINT GREEN (-2873 1983);
FORCEPROP 2 LAST CDS_LIB mstr_standard
J 0
(-2875 1975);
PAINT MONO (-2875 1975);
DISPLAY INVISIBLE (-2875 1975);
FORCEPROP 1 LAST BODY_TYPE PLUMBING
J 2
(-2875 1925);
DISPLAY 1.595745 (-2875 1925);
PAINT GREEN (-2875 1925);
DISPLAY INVISIBLE (-2875 1925);
FORCEPROP 1 LAST HDL_TAP TRUE
J 2
(-3200 1850);
DISPLAY 1.595745 (-3200 1850);
PAINT GREEN (-3200 1850);
DISPLAY INVISIBLE (-3200 1850);
FORCEPROP 1 LAST PATH I108
J 2
(-2873 1975);
DISPLAY 0.872340 (-2873 1975);
PAINT GREEN (-2873 1975);
DISPLAY INVISIBLE (-2873 1975);
FORCEADD TAP..6
R 2
(-2875 2075);
FORCEPROP 3 LASTPIN (-2925 2075) SIG_NAME M_H_MA<3>
J 0
(-2915 2085);
DISPLAY 0.659574 (-2915 2085);
PAINT MONO (-2915 2085);
DISPLAY INVISIBLE (-2915 2085);
FORCEPROP 1 LASTPIN (-2925 2075) BN 3
J 2
(-2873 2083);
DISPLAY 0.617021 (-2873 2083);
PAINT GREEN (-2873 2083);
FORCEPROP 2 LAST CDS_LIB mstr_standard
J 0
(-2875 2075);
PAINT MONO (-2875 2075);
DISPLAY INVISIBLE (-2875 2075);
FORCEPROP 1 LAST BODY_TYPE PLUMBING
J 2
(-2875 2025);
DISPLAY 1.595745 (-2875 2025);
PAINT GREEN (-2875 2025);
DISPLAY INVISIBLE (-2875 2025);
FORCEPROP 1 LAST HDL_TAP TRUE
J 2
(-3200 1950);
DISPLAY 1.595745 (-3200 1950);
PAINT GREEN (-3200 1950);
DISPLAY INVISIBLE (-3200 1950);
FORCEPROP 1 LAST PATH I109
J 2
(-2873 2075);
DISPLAY 0.872340 (-2873 2075);
PAINT GREEN (-2873 2075);
DISPLAY INVISIBLE (-2873 2075);
FORCEADD TAP..6
(-5600 925);
FORCEPROP 3 LASTPIN (-5550 925) SIG_NAME M_H_CLK_DP<2>
J 0
(-5540 935);
DISPLAY 0.659574 (-5540 935);
PAINT MONO (-5540 935);
DISPLAY INVISIBLE (-5540 935);
FORCEPROP 1 LASTPIN (-5550 925) BN 2
J 0
(-5602 933);
DISPLAY 0.617021 (-5602 933);
PAINT GREEN (-5602 933);
FORCEPROP 2 LAST CDS_LIB mstr_standard
J 0
(-5600 925);
PAINT MONO (-5600 925);
DISPLAY INVISIBLE (-5600 925);
FORCEPROP 1 LAST BODY_TYPE PLUMBING
J 0
(-5600 875);
DISPLAY 1.595745 (-5600 875);
PAINT GREEN (-5600 875);
DISPLAY INVISIBLE (-5600 875);
FORCEPROP 1 LAST HDL_TAP TRUE
J 0
(-5275 800);
DISPLAY 1.595745 (-5275 800);
PAINT GREEN (-5275 800);
DISPLAY INVISIBLE (-5275 800);
FORCEPROP 1 LAST PATH I11
J 0
(-5602 925);
DISPLAY 0.872340 (-5602 925);
PAINT GREEN (-5602 925);
DISPLAY INVISIBLE (-5602 925);
FORCEADD TAP..6
R 2
(-2875 2025);
FORCEPROP 3 LASTPIN (-2925 2025) SIG_NAME M_H_MA<2>
J 0
(-2915 2035);
DISPLAY 0.659574 (-2915 2035);
PAINT MONO (-2915 2035);
DISPLAY INVISIBLE (-2915 2035);
FORCEPROP 1 LASTPIN (-2925 2025) BN 2
J 2
(-2873 2033);
DISPLAY 0.617021 (-2873 2033);
PAINT GREEN (-2873 2033);
FORCEPROP 2 LAST CDS_LIB mstr_standard
J 0
(-2875 2025);
PAINT MONO (-2875 2025);
DISPLAY INVISIBLE (-2875 2025);
FORCEPROP 1 LAST BODY_TYPE PLUMBING
J 2
(-2875 1975);
DISPLAY 1.595745 (-2875 1975);
PAINT GREEN (-2875 1975);
DISPLAY INVISIBLE (-2875 1975);
FORCEPROP 1 LAST HDL_TAP TRUE
J 2
(-3200 1900);
DISPLAY 1.595745 (-3200 1900);
PAINT GREEN (-3200 1900);
DISPLAY INVISIBLE (-3200 1900);
FORCEPROP 1 LAST PATH I110
J 2
(-2873 2025);
DISPLAY 0.872340 (-2873 2025);
PAINT GREEN (-2873 2025);
DISPLAY INVISIBLE (-2873 2025);
FORCEADD TAP..6
R 2
(-2875 2125);
FORCEPROP 3 LASTPIN (-2925 2125) SIG_NAME M_H_MA<4>
J 0
(-2915 2135);
DISPLAY 0.659574 (-2915 2135);
PAINT MONO (-2915 2135);
DISPLAY INVISIBLE (-2915 2135);
FORCEPROP 1 LASTPIN (-2925 2125) BN 4
J 2
(-2873 2133);
DISPLAY 0.617021 (-2873 2133);
PAINT GREEN (-2873 2133);
FORCEPROP 2 LAST CDS_LIB mstr_standard
J 0
(-2875 2125);
PAINT MONO (-2875 2125);
DISPLAY INVISIBLE (-2875 2125);
FORCEPROP 1 LAST BODY_TYPE PLUMBING
J 2
(-2875 2075);
DISPLAY 1.595745 (-2875 2075);
PAINT GREEN (-2875 2075);
DISPLAY INVISIBLE (-2875 2075);
FORCEPROP 1 LAST HDL_TAP TRUE
J 2
(-3200 2000);
DISPLAY 1.595745 (-3200 2000);
PAINT GREEN (-3200 2000);
DISPLAY INVISIBLE (-3200 2000);
FORCEPROP 1 LAST PATH I111
J 2
(-2873 2125);
DISPLAY 0.872340 (-2873 2125);
PAINT GREEN (-2873 2125);
DISPLAY INVISIBLE (-2873 2125);
FORCEADD TAP..6
R 2
(-2875 2175);
FORCEPROP 3 LASTPIN (-2925 2175) SIG_NAME M_H_MA<5>
J 0
(-2915 2185);
DISPLAY 0.659574 (-2915 2185);
PAINT MONO (-2915 2185);
DISPLAY INVISIBLE (-2915 2185);
FORCEPROP 1 LASTPIN (-2925 2175) BN 5
J 2
(-2873 2183);
DISPLAY 0.617021 (-2873 2183);
PAINT GREEN (-2873 2183);
FORCEPROP 2 LAST CDS_LIB mstr_standard
J 0
(-2875 2175);
PAINT MONO (-2875 2175);
DISPLAY INVISIBLE (-2875 2175);
FORCEPROP 1 LAST BODY_TYPE PLUMBING
J 2
(-2875 2125);
DISPLAY 1.595745 (-2875 2125);
PAINT GREEN (-2875 2125);
DISPLAY INVISIBLE (-2875 2125);
FORCEPROP 1 LAST HDL_TAP TRUE
J 2
(-3200 2050);
DISPLAY 1.595745 (-3200 2050);
PAINT GREEN (-3200 2050);
DISPLAY INVISIBLE (-3200 2050);
FORCEPROP 1 LAST PATH I112
J 2
(-2873 2175);
DISPLAY 0.872340 (-2873 2175);
PAINT GREEN (-2873 2175);
DISPLAY INVISIBLE (-2873 2175);
FORCEADD TAP..6
R 2
(-2875 2225);
FORCEPROP 3 LASTPIN (-2925 2225) SIG_NAME M_H_MA<6>
J 0
(-2915 2235);
DISPLAY 0.659574 (-2915 2235);
PAINT MONO (-2915 2235);
DISPLAY INVISIBLE (-2915 2235);
FORCEPROP 1 LASTPIN (-2925 2225) BN 6
J 2
(-2873 2233);
DISPLAY 0.617021 (-2873 2233);
PAINT GREEN (-2873 2233);
FORCEPROP 2 LAST CDS_LIB mstr_standard
J 0
(-2875 2225);
PAINT MONO (-2875 2225);
DISPLAY INVISIBLE (-2875 2225);
FORCEPROP 1 LAST BODY_TYPE PLUMBING
J 2
(-2875 2175);
DISPLAY 1.595745 (-2875 2175);
PAINT GREEN (-2875 2175);
DISPLAY INVISIBLE (-2875 2175);
FORCEPROP 1 LAST HDL_TAP TRUE
J 2
(-3200 2100);
DISPLAY 1.595745 (-3200 2100);
PAINT GREEN (-3200 2100);
DISPLAY INVISIBLE (-3200 2100);
FORCEPROP 1 LAST PATH I113
J 2
(-2873 2225);
DISPLAY 0.872340 (-2873 2225);
PAINT GREEN (-2873 2225);
DISPLAY INVISIBLE (-2873 2225);
FORCEADD TAP..6
R 2
(-2875 2325);
FORCEPROP 3 LASTPIN (-2925 2325) SIG_NAME M_H_MA<8>
J 0
(-2915 2335);
DISPLAY 0.659574 (-2915 2335);
PAINT MONO (-2915 2335);
DISPLAY INVISIBLE (-2915 2335);
FORCEPROP 1 LASTPIN (-2925 2325) BN 8
J 2
(-2873 2333);
DISPLAY 0.617021 (-2873 2333);
PAINT GREEN (-2873 2333);
FORCEPROP 2 LAST CDS_LIB mstr_standard
J 0
(-2875 2325);
PAINT MONO (-2875 2325);
DISPLAY INVISIBLE (-2875 2325);
FORCEPROP 1 LAST BODY_TYPE PLUMBING
J 2
(-2875 2275);
DISPLAY 1.595745 (-2875 2275);
PAINT GREEN (-2875 2275);
DISPLAY INVISIBLE (-2875 2275);
FORCEPROP 1 LAST HDL_TAP TRUE
J 2
(-3200 2200);
DISPLAY 1.595745 (-3200 2200);
PAINT GREEN (-3200 2200);
DISPLAY INVISIBLE (-3200 2200);
FORCEPROP 1 LAST PATH I114
J 2
(-2873 2325);
DISPLAY 0.872340 (-2873 2325);
PAINT GREEN (-2873 2325);
DISPLAY INVISIBLE (-2873 2325);
FORCEADD TAP..6
R 2
(-2875 2275);
FORCEPROP 3 LASTPIN (-2925 2275) SIG_NAME M_H_MA<7>
J 0
(-2915 2285);
DISPLAY 0.659574 (-2915 2285);
PAINT MONO (-2915 2285);
DISPLAY INVISIBLE (-2915 2285);
FORCEPROP 1 LASTPIN (-2925 2275) BN 7
J 2
(-2873 2283);
DISPLAY 0.617021 (-2873 2283);
PAINT GREEN (-2873 2283);
FORCEPROP 2 LAST CDS_LIB mstr_standard
J 0
(-2875 2275);
PAINT MONO (-2875 2275);
DISPLAY INVISIBLE (-2875 2275);
FORCEPROP 1 LAST BODY_TYPE PLUMBING
J 2
(-2875 2225);
DISPLAY 1.595745 (-2875 2225);
PAINT GREEN (-2875 2225);
DISPLAY INVISIBLE (-2875 2225);
FORCEPROP 1 LAST HDL_TAP TRUE
J 2
(-3200 2150);
DISPLAY 1.595745 (-3200 2150);
PAINT GREEN (-3200 2150);
DISPLAY INVISIBLE (-3200 2150);
FORCEPROP 1 LAST PATH I115
J 2
(-2873 2275);
DISPLAY 0.872340 (-2873 2275);
PAINT GREEN (-2873 2275);
DISPLAY INVISIBLE (-2873 2275);
FORCEADD TAP..6
R 2
(-2875 2475);
FORCEPROP 3 LASTPIN (-2925 2475) SIG_NAME M_H_MA<11>
J 0
(-2915 2485);
DISPLAY 0.659574 (-2915 2485);
PAINT MONO (-2915 2485);
DISPLAY INVISIBLE (-2915 2485);
FORCEPROP 1 LASTPIN (-2925 2475) BN 11
J 2
(-2873 2483);
DISPLAY 0.617021 (-2873 2483);
PAINT GREEN (-2873 2483);
FORCEPROP 2 LAST CDS_LIB mstr_standard
J 0
(-2875 2475);
PAINT MONO (-2875 2475);
DISPLAY INVISIBLE (-2875 2475);
FORCEPROP 1 LAST BODY_TYPE PLUMBING
J 2
(-2875 2425);
DISPLAY 1.595745 (-2875 2425);
PAINT GREEN (-2875 2425);
DISPLAY INVISIBLE (-2875 2425);
FORCEPROP 1 LAST HDL_TAP TRUE
J 2
(-3200 2350);
DISPLAY 1.595745 (-3200 2350);
PAINT GREEN (-3200 2350);
DISPLAY INVISIBLE (-3200 2350);
FORCEPROP 1 LAST PATH I116
J 2
(-2873 2475);
DISPLAY 0.872340 (-2873 2475);
PAINT GREEN (-2873 2475);
DISPLAY INVISIBLE (-2873 2475);
FORCEADD TAP..6
R 2
(-2875 2425);
FORCEPROP 3 LASTPIN (-2925 2425) SIG_NAME M_H_MA<10>
J 0
(-2915 2435);
DISPLAY 0.659574 (-2915 2435);
PAINT MONO (-2915 2435);
DISPLAY INVISIBLE (-2915 2435);
FORCEPROP 1 LASTPIN (-2925 2425) BN 10
J 2
(-2873 2433);
DISPLAY 0.617021 (-2873 2433);
PAINT GREEN (-2873 2433);
FORCEPROP 2 LAST CDS_LIB mstr_standard
J 0
(-2875 2425);
PAINT MONO (-2875 2425);
DISPLAY INVISIBLE (-2875 2425);
FORCEPROP 1 LAST BODY_TYPE PLUMBING
J 2
(-2875 2375);
DISPLAY 1.595745 (-2875 2375);
PAINT GREEN (-2875 2375);
DISPLAY INVISIBLE (-2875 2375);
FORCEPROP 1 LAST HDL_TAP TRUE
J 2
(-3200 2300);
DISPLAY 1.595745 (-3200 2300);
PAINT GREEN (-3200 2300);
DISPLAY INVISIBLE (-3200 2300);
FORCEPROP 1 LAST PATH I117
J 2
(-2873 2425);
DISPLAY 0.872340 (-2873 2425);
PAINT GREEN (-2873 2425);
DISPLAY INVISIBLE (-2873 2425);
FORCEADD TAP..6
R 2
(-2875 2375);
FORCEPROP 3 LASTPIN (-2925 2375) SIG_NAME M_H_MA<9>
J 0
(-2915 2385);
DISPLAY 0.659574 (-2915 2385);
PAINT MONO (-2915 2385);
DISPLAY INVISIBLE (-2915 2385);
FORCEPROP 1 LASTPIN (-2925 2375) BN 9
J 2
(-2873 2383);
DISPLAY 0.617021 (-2873 2383);
PAINT GREEN (-2873 2383);
FORCEPROP 2 LAST CDS_LIB mstr_standard
J 0
(-2875 2375);
PAINT MONO (-2875 2375);
DISPLAY INVISIBLE (-2875 2375);
FORCEPROP 1 LAST BODY_TYPE PLUMBING
J 2
(-2875 2325);
DISPLAY 1.595745 (-2875 2325);
PAINT GREEN (-2875 2325);
DISPLAY INVISIBLE (-2875 2325);
FORCEPROP 1 LAST HDL_TAP TRUE
J 2
(-3200 2250);
DISPLAY 1.595745 (-3200 2250);
PAINT GREEN (-3200 2250);
DISPLAY INVISIBLE (-3200 2250);
FORCEPROP 1 LAST PATH I118
J 2
(-2873 2375);
DISPLAY 0.872340 (-2873 2375);
PAINT GREEN (-2873 2375);
DISPLAY INVISIBLE (-2873 2375);
FORCEADD TAP..6
R 2
(-2875 2525);
FORCEPROP 3 LASTPIN (-2925 2525) SIG_NAME M_H_MA<12>
J 0
(-2915 2535);
DISPLAY 0.659574 (-2915 2535);
PAINT MONO (-2915 2535);
DISPLAY INVISIBLE (-2915 2535);
FORCEPROP 1 LASTPIN (-2925 2525) BN 12
J 2
(-2873 2533);
DISPLAY 0.617021 (-2873 2533);
PAINT GREEN (-2873 2533);
FORCEPROP 2 LAST CDS_LIB mstr_standard
J 0
(-2875 2525);
PAINT MONO (-2875 2525);
DISPLAY INVISIBLE (-2875 2525);
FORCEPROP 1 LAST BODY_TYPE PLUMBING
J 2
(-2875 2475);
DISPLAY 1.595745 (-2875 2475);
PAINT GREEN (-2875 2475);
DISPLAY INVISIBLE (-2875 2475);
FORCEPROP 1 LAST HDL_TAP TRUE
J 2
(-3200 2400);
DISPLAY 1.595745 (-3200 2400);
PAINT GREEN (-3200 2400);
DISPLAY INVISIBLE (-3200 2400);
FORCEPROP 1 LAST PATH I119
J 2
(-2873 2525);
DISPLAY 0.872340 (-2873 2525);
PAINT GREEN (-2873 2525);
DISPLAY INVISIBLE (-2873 2525);
FORCEADD TAP..6
(-5600 975);
FORCEPROP 3 LASTPIN (-5550 975) SIG_NAME M_H_CLK_DP<3>
J 0
(-5540 985);
DISPLAY 0.659574 (-5540 985);
PAINT MONO (-5540 985);
DISPLAY INVISIBLE (-5540 985);
FORCEPROP 1 LASTPIN (-5550 975) BN 3
J 0
(-5602 983);
DISPLAY 0.617021 (-5602 983);
PAINT GREEN (-5602 983);
FORCEPROP 2 LAST CDS_LIB mstr_standard
J 0
(-5600 975);
PAINT MONO (-5600 975);
DISPLAY INVISIBLE (-5600 975);
FORCEPROP 1 LAST BODY_TYPE PLUMBING
J 0
(-5600 925);
DISPLAY 1.595745 (-5600 925);
PAINT GREEN (-5600 925);
DISPLAY INVISIBLE (-5600 925);
FORCEPROP 1 LAST HDL_TAP TRUE
J 0
(-5275 850);
DISPLAY 1.595745 (-5275 850);
PAINT GREEN (-5275 850);
DISPLAY INVISIBLE (-5275 850);
FORCEPROP 1 LAST PATH I12
J 0
(-5602 975);
DISPLAY 0.872340 (-5602 975);
PAINT GREEN (-5602 975);
DISPLAY INVISIBLE (-5602 975);
FORCEADD TAP..6
R 2
(-2875 2575);
FORCEPROP 3 LASTPIN (-2925 2575) SIG_NAME M_H_MA<13>
J 0
(-2915 2585);
DISPLAY 0.659574 (-2915 2585);
PAINT MONO (-2915 2585);
DISPLAY INVISIBLE (-2915 2585);
FORCEPROP 1 LASTPIN (-2925 2575) BN 13
J 2
(-2873 2583);
DISPLAY 0.617021 (-2873 2583);
PAINT GREEN (-2873 2583);
FORCEPROP 2 LAST CDS_LIB mstr_standard
J 0
(-2875 2575);
PAINT MONO (-2875 2575);
DISPLAY INVISIBLE (-2875 2575);
FORCEPROP 1 LAST BODY_TYPE PLUMBING
J 2
(-2875 2525);
DISPLAY 1.595745 (-2875 2525);
PAINT GREEN (-2875 2525);
DISPLAY INVISIBLE (-2875 2525);
FORCEPROP 1 LAST HDL_TAP TRUE
J 2
(-3200 2450);
DISPLAY 1.595745 (-3200 2450);
PAINT GREEN (-3200 2450);
DISPLAY INVISIBLE (-3200 2450);
FORCEPROP 1 LAST PATH I120
J 2
(-2873 2575);
DISPLAY 0.872340 (-2873 2575);
PAINT GREEN (-2873 2575);
DISPLAY INVISIBLE (-2873 2575);
FORCEADD TAP..6
R 2
(-2875 2625);
FORCEPROP 3 LASTPIN (-2925 2625) SIG_NAME M_H_MA<14>
J 0
(-2915 2635);
DISPLAY 0.659574 (-2915 2635);
PAINT MONO (-2915 2635);
DISPLAY INVISIBLE (-2915 2635);
FORCEPROP 1 LASTPIN (-2925 2625) BN 14
J 2
(-2873 2633);
DISPLAY 0.617021 (-2873 2633);
PAINT GREEN (-2873 2633);
FORCEPROP 2 LAST CDS_LIB mstr_standard
J 0
(-2875 2625);
PAINT MONO (-2875 2625);
DISPLAY INVISIBLE (-2875 2625);
FORCEPROP 1 LAST BODY_TYPE PLUMBING
J 2
(-2875 2575);
DISPLAY 1.595745 (-2875 2575);
PAINT GREEN (-2875 2575);
DISPLAY INVISIBLE (-2875 2575);
FORCEPROP 1 LAST HDL_TAP TRUE
J 2
(-3200 2500);
DISPLAY 1.595745 (-3200 2500);
PAINT GREEN (-3200 2500);
DISPLAY INVISIBLE (-3200 2500);
FORCEPROP 1 LAST PATH I121
J 2
(-2873 2625);
DISPLAY 0.872340 (-2873 2625);
PAINT GREEN (-2873 2625);
DISPLAY INVISIBLE (-2873 2625);
FORCEADD TAP..6
R 2
(-2875 2675);
FORCEPROP 3 LASTPIN (-2925 2675) SIG_NAME M_H_MA<15>
J 0
(-2915 2685);
DISPLAY 0.659574 (-2915 2685);
PAINT MONO (-2915 2685);
DISPLAY INVISIBLE (-2915 2685);
FORCEPROP 1 LASTPIN (-2925 2675) BN 15
J 2
(-2873 2683);
DISPLAY 0.617021 (-2873 2683);
PAINT GREEN (-2873 2683);
FORCEPROP 2 LAST CDS_LIB mstr_standard
J 0
(-2875 2675);
PAINT MONO (-2875 2675);
DISPLAY INVISIBLE (-2875 2675);
FORCEPROP 1 LAST BODY_TYPE PLUMBING
J 2
(-2875 2625);
DISPLAY 1.595745 (-2875 2625);
PAINT GREEN (-2875 2625);
DISPLAY INVISIBLE (-2875 2625);
FORCEPROP 1 LAST HDL_TAP TRUE
J 2
(-3200 2550);
DISPLAY 1.595745 (-3200 2550);
PAINT GREEN (-3200 2550);
DISPLAY INVISIBLE (-3200 2550);
FORCEPROP 1 LAST PATH I122
J 2
(-2873 2675);
DISPLAY 0.872340 (-2873 2675);
PAINT GREEN (-2873 2675);
DISPLAY INVISIBLE (-2873 2675);
FORCEADD TAP..6
R 2
(-2875 2725);
FORCEPROP 3 LASTPIN (-2925 2725) SIG_NAME M_H_MA<16>
J 0
(-2915 2735);
DISPLAY 0.659574 (-2915 2735);
PAINT MONO (-2915 2735);
DISPLAY INVISIBLE (-2915 2735);
FORCEPROP 1 LASTPIN (-2925 2725) BN 16
J 2
(-2873 2733);
DISPLAY 0.617021 (-2873 2733);
PAINT GREEN (-2873 2733);
FORCEPROP 2 LAST CDS_LIB mstr_standard
J 0
(-2875 2725);
PAINT MONO (-2875 2725);
DISPLAY INVISIBLE (-2875 2725);
FORCEPROP 1 LAST BODY_TYPE PLUMBING
J 2
(-2875 2675);
DISPLAY 1.595745 (-2875 2675);
PAINT GREEN (-2875 2675);
DISPLAY INVISIBLE (-2875 2675);
FORCEPROP 1 LAST HDL_TAP TRUE
J 2
(-3200 2600);
DISPLAY 1.595745 (-3200 2600);
PAINT GREEN (-3200 2600);
DISPLAY INVISIBLE (-3200 2600);
FORCEPROP 1 LAST PATH I123
J 2
(-2873 2725);
DISPLAY 0.872340 (-2873 2725);
PAINT GREEN (-2873 2725);
DISPLAY INVISIBLE (-2873 2725);
FORCEADD TAP..6
R 2
(-2875 2775);
FORCEPROP 3 LASTPIN (-2925 2775) SIG_NAME M_H_MA<17>
J 0
(-2915 2785);
DISPLAY 0.659574 (-2915 2785);
PAINT MONO (-2915 2785);
DISPLAY INVISIBLE (-2915 2785);
FORCEPROP 1 LASTPIN (-2925 2775) BN 17
J 2
(-2873 2783);
DISPLAY 0.617021 (-2873 2783);
PAINT GREEN (-2873 2783);
FORCEPROP 2 LAST CDS_LIB mstr_standard
J 0
(-2875 2775);
PAINT MONO (-2875 2775);
DISPLAY INVISIBLE (-2875 2775);
FORCEPROP 1 LAST BODY_TYPE PLUMBING
J 2
(-2875 2725);
DISPLAY 1.595745 (-2875 2725);
PAINT GREEN (-2875 2725);
DISPLAY INVISIBLE (-2875 2725);
FORCEPROP 1 LAST HDL_TAP TRUE
J 2
(-3200 2650);
DISPLAY 1.595745 (-3200 2650);
PAINT GREEN (-3200 2650);
DISPLAY INVISIBLE (-3200 2650);
FORCEPROP 1 LAST PATH I124
J 2
(-2873 2775);
DISPLAY 0.872340 (-2873 2775);
PAINT GREEN (-2873 2775);
DISPLAY INVISIBLE (-2873 2775);
FORCEADD TAP..6
R 2
(-2875 2925);
FORCEPROP 3 LASTPIN (-2925 2925) SIG_NAME M_H_DQS_DN<1>
J 0
(-2915 2935);
DISPLAY 0.659574 (-2915 2935);
PAINT MONO (-2915 2935);
DISPLAY INVISIBLE (-2915 2935);
FORCEPROP 1 LASTPIN (-2925 2925) BN 1
J 2
(-2873 2933);
DISPLAY 0.617021 (-2873 2933);
PAINT GREEN (-2873 2933);
FORCEPROP 2 LAST CDS_LIB mstr_standard
J 0
(-2875 2925);
PAINT MONO (-2875 2925);
DISPLAY INVISIBLE (-2875 2925);
FORCEPROP 1 LAST BODY_TYPE PLUMBING
J 2
(-2875 2875);
DISPLAY 1.595745 (-2875 2875);
PAINT GREEN (-2875 2875);
DISPLAY INVISIBLE (-2875 2875);
FORCEPROP 1 LAST HDL_TAP TRUE
J 2
(-3200 2800);
DISPLAY 1.595745 (-3200 2800);
PAINT GREEN (-3200 2800);
DISPLAY INVISIBLE (-3200 2800);
FORCEPROP 1 LAST PATH I125
J 2
(-2873 2925);
DISPLAY 0.872340 (-2873 2925);
PAINT GREEN (-2873 2925);
DISPLAY INVISIBLE (-2873 2925);
FORCEADD TAP..6
R 2
(-2875 2975);
FORCEPROP 3 LASTPIN (-2925 2975) SIG_NAME M_H_DQS_DN<2>
J 0
(-2915 2985);
DISPLAY 0.659574 (-2915 2985);
PAINT MONO (-2915 2985);
DISPLAY INVISIBLE (-2915 2985);
FORCEPROP 1 LASTPIN (-2925 2975) BN 2
J 2
(-2873 2983);
DISPLAY 0.617021 (-2873 2983);
PAINT GREEN (-2873 2983);
FORCEPROP 2 LAST CDS_LIB mstr_standard
J 0
(-2875 2975);
PAINT MONO (-2875 2975);
DISPLAY INVISIBLE (-2875 2975);
FORCEPROP 1 LAST BODY_TYPE PLUMBING
J 2
(-2875 2925);
DISPLAY 1.595745 (-2875 2925);
PAINT GREEN (-2875 2925);
DISPLAY INVISIBLE (-2875 2925);
FORCEPROP 1 LAST HDL_TAP TRUE
J 2
(-3200 2850);
DISPLAY 1.595745 (-3200 2850);
PAINT GREEN (-3200 2850);
DISPLAY INVISIBLE (-3200 2850);
FORCEPROP 1 LAST PATH I126
J 2
(-2873 2975);
DISPLAY 0.872340 (-2873 2975);
PAINT GREEN (-2873 2975);
DISPLAY INVISIBLE (-2873 2975);
FORCEADD TAP..6
R 2
(-2875 2875);
FORCEPROP 3 LASTPIN (-2925 2875) SIG_NAME M_H_DQS_DN<0>
J 0
(-2915 2885);
DISPLAY 0.659574 (-2915 2885);
PAINT MONO (-2915 2885);
DISPLAY INVISIBLE (-2915 2885);
FORCEPROP 1 LASTPIN (-2925 2875) BN 0
J 2
(-2873 2883);
DISPLAY 0.617021 (-2873 2883);
PAINT GREEN (-2873 2883);
FORCEPROP 2 LAST CDS_LIB mstr_standard
J 0
(-2875 2875);
PAINT MONO (-2875 2875);
DISPLAY INVISIBLE (-2875 2875);
FORCEPROP 1 LAST BODY_TYPE PLUMBING
J 2
(-2875 2825);
DISPLAY 1.595745 (-2875 2825);
PAINT GREEN (-2875 2825);
DISPLAY INVISIBLE (-2875 2825);
FORCEPROP 1 LAST HDL_TAP TRUE
J 2
(-3200 2750);
DISPLAY 1.595745 (-3200 2750);
PAINT GREEN (-3200 2750);
DISPLAY INVISIBLE (-3200 2750);
FORCEPROP 1 LAST PATH I127
J 2
(-2873 2875);
DISPLAY 0.872340 (-2873 2875);
PAINT GREEN (-2873 2875);
DISPLAY INVISIBLE (-2873 2875);
FORCEADD TAP..6
R 2
(-2875 3075);
FORCEPROP 3 LASTPIN (-2925 3075) SIG_NAME M_H_DQS_DN<4>
J 0
(-2915 3085);
DISPLAY 0.659574 (-2915 3085);
PAINT MONO (-2915 3085);
DISPLAY INVISIBLE (-2915 3085);
FORCEPROP 1 LASTPIN (-2925 3075) BN 4
J 2
(-2873 3083);
DISPLAY 0.617021 (-2873 3083);
PAINT GREEN (-2873 3083);
FORCEPROP 2 LAST CDS_LIB mstr_standard
J 0
(-2875 3075);
PAINT MONO (-2875 3075);
DISPLAY INVISIBLE (-2875 3075);
FORCEPROP 1 LAST BODY_TYPE PLUMBING
J 2
(-2875 3025);
DISPLAY 1.595745 (-2875 3025);
PAINT GREEN (-2875 3025);
DISPLAY INVISIBLE (-2875 3025);
FORCEPROP 1 LAST HDL_TAP TRUE
J 2
(-3200 2950);
DISPLAY 1.595745 (-3200 2950);
PAINT GREEN (-3200 2950);
DISPLAY INVISIBLE (-3200 2950);
FORCEPROP 1 LAST PATH I128
J 2
(-2873 3075);
DISPLAY 0.872340 (-2873 3075);
PAINT GREEN (-2873 3075);
DISPLAY INVISIBLE (-2873 3075);
FORCEADD TAP..6
R 2
(-2875 3025);
FORCEPROP 3 LASTPIN (-2925 3025) SIG_NAME M_H_DQS_DN<3>
J 0
(-2915 3035);
DISPLAY 0.659574 (-2915 3035);
PAINT MONO (-2915 3035);
DISPLAY INVISIBLE (-2915 3035);
FORCEPROP 1 LASTPIN (-2925 3025) BN 3
J 2
(-2873 3033);
DISPLAY 0.617021 (-2873 3033);
PAINT GREEN (-2873 3033);
FORCEPROP 2 LAST CDS_LIB mstr_standard
J 0
(-2875 3025);
PAINT MONO (-2875 3025);
DISPLAY INVISIBLE (-2875 3025);
FORCEPROP 1 LAST BODY_TYPE PLUMBING
J 2
(-2875 2975);
DISPLAY 1.595745 (-2875 2975);
PAINT GREEN (-2875 2975);
DISPLAY INVISIBLE (-2875 2975);
FORCEPROP 1 LAST HDL_TAP TRUE
J 2
(-3200 2900);
DISPLAY 1.595745 (-3200 2900);
PAINT GREEN (-3200 2900);
DISPLAY INVISIBLE (-3200 2900);
FORCEPROP 1 LAST PATH I129
J 2
(-2873 3025);
DISPLAY 0.872340 (-2873 3025);
PAINT GREEN (-2873 3025);
DISPLAY INVISIBLE (-2873 3025);
FORCEADD TAP..6
(-5600 1075);
FORCEPROP 3 LASTPIN (-5550 1075) SIG_NAME M_H_ECC<0>
J 0
(-5540 1085);
DISPLAY 0.659574 (-5540 1085);
PAINT MONO (-5540 1085);
DISPLAY INVISIBLE (-5540 1085);
FORCEPROP 1 LASTPIN (-5550 1075) BN 0
J 0
(-5602 1083);
DISPLAY 0.617021 (-5602 1083);
PAINT GREEN (-5602 1083);
FORCEPROP 2 LAST CDS_LIB mstr_standard
J 0
(-5600 1075);
PAINT MONO (-5600 1075);
DISPLAY INVISIBLE (-5600 1075);
FORCEPROP 1 LAST BODY_TYPE PLUMBING
J 0
(-5600 1025);
DISPLAY 1.595745 (-5600 1025);
PAINT GREEN (-5600 1025);
DISPLAY INVISIBLE (-5600 1025);
FORCEPROP 1 LAST HDL_TAP TRUE
J 0
(-5275 950);
DISPLAY 1.595745 (-5275 950);
PAINT GREEN (-5275 950);
DISPLAY INVISIBLE (-5275 950);
FORCEPROP 1 LAST PATH I13
J 0
(-5602 1075);
DISPLAY 0.872340 (-5602 1075);
PAINT GREEN (-5602 1075);
DISPLAY INVISIBLE (-5602 1075);
FORCEADD TAP..6
R 2
(-2875 3125);
FORCEPROP 3 LASTPIN (-2925 3125) SIG_NAME M_H_DQS_DN<5>
J 0
(-2915 3135);
DISPLAY 0.659574 (-2915 3135);
PAINT MONO (-2915 3135);
DISPLAY INVISIBLE (-2915 3135);
FORCEPROP 1 LASTPIN (-2925 3125) BN 5
J 2
(-2873 3133);
DISPLAY 0.617021 (-2873 3133);
PAINT GREEN (-2873 3133);
FORCEPROP 2 LAST CDS_LIB mstr_standard
J 0
(-2875 3125);
PAINT MONO (-2875 3125);
DISPLAY INVISIBLE (-2875 3125);
FORCEPROP 1 LAST BODY_TYPE PLUMBING
J 2
(-2875 3075);
DISPLAY 1.595745 (-2875 3075);
PAINT GREEN (-2875 3075);
DISPLAY INVISIBLE (-2875 3075);
FORCEPROP 1 LAST HDL_TAP TRUE
J 2
(-3200 3000);
DISPLAY 1.595745 (-3200 3000);
PAINT GREEN (-3200 3000);
DISPLAY INVISIBLE (-3200 3000);
FORCEPROP 1 LAST PATH I130
J 2
(-2873 3125);
DISPLAY 0.872340 (-2873 3125);
PAINT GREEN (-2873 3125);
DISPLAY INVISIBLE (-2873 3125);
FORCEADD TAP..6
R 2
(-2875 3175);
FORCEPROP 3 LASTPIN (-2925 3175) SIG_NAME M_H_DQS_DN<6>
J 0
(-2915 3185);
DISPLAY 0.659574 (-2915 3185);
PAINT MONO (-2915 3185);
DISPLAY INVISIBLE (-2915 3185);
FORCEPROP 1 LASTPIN (-2925 3175) BN 6
J 2
(-2873 3183);
DISPLAY 0.617021 (-2873 3183);
PAINT GREEN (-2873 3183);
FORCEPROP 2 LAST CDS_LIB mstr_standard
J 0
(-2875 3175);
PAINT MONO (-2875 3175);
DISPLAY INVISIBLE (-2875 3175);
FORCEPROP 1 LAST BODY_TYPE PLUMBING
J 2
(-2875 3125);
DISPLAY 1.595745 (-2875 3125);
PAINT GREEN (-2875 3125);
DISPLAY INVISIBLE (-2875 3125);
FORCEPROP 1 LAST HDL_TAP TRUE
J 2
(-3200 3050);
DISPLAY 1.595745 (-3200 3050);
PAINT GREEN (-3200 3050);
DISPLAY INVISIBLE (-3200 3050);
FORCEPROP 1 LAST PATH I131
J 2
(-2873 3175);
DISPLAY 0.872340 (-2873 3175);
PAINT GREEN (-2873 3175);
DISPLAY INVISIBLE (-2873 3175);
FORCEADD TAP..6
R 2
(-2875 3225);
FORCEPROP 3 LASTPIN (-2925 3225) SIG_NAME M_H_DQS_DN<7>
J 0
(-2915 3235);
DISPLAY 0.659574 (-2915 3235);
PAINT MONO (-2915 3235);
DISPLAY INVISIBLE (-2915 3235);
FORCEPROP 1 LASTPIN (-2925 3225) BN 7
J 2
(-2873 3233);
DISPLAY 0.617021 (-2873 3233);
PAINT GREEN (-2873 3233);
FORCEPROP 2 LAST CDS_LIB mstr_standard
J 0
(-2875 3225);
PAINT MONO (-2875 3225);
DISPLAY INVISIBLE (-2875 3225);
FORCEPROP 1 LAST BODY_TYPE PLUMBING
J 2
(-2875 3175);
DISPLAY 1.595745 (-2875 3175);
PAINT GREEN (-2875 3175);
DISPLAY INVISIBLE (-2875 3175);
FORCEPROP 1 LAST HDL_TAP TRUE
J 2
(-3200 3100);
DISPLAY 1.595745 (-3200 3100);
PAINT GREEN (-3200 3100);
DISPLAY INVISIBLE (-3200 3100);
FORCEPROP 1 LAST PATH I132
J 2
(-2873 3225);
DISPLAY 0.872340 (-2873 3225);
PAINT GREEN (-2873 3225);
DISPLAY INVISIBLE (-2873 3225);
FORCEADD TAP..6
R 2
(-2875 3275);
FORCEPROP 3 LASTPIN (-2925 3275) SIG_NAME M_H_DQS_DN<8>
J 0
(-2915 3285);
DISPLAY 0.659574 (-2915 3285);
PAINT MONO (-2915 3285);
DISPLAY INVISIBLE (-2915 3285);
FORCEPROP 1 LASTPIN (-2925 3275) BN 8
J 2
(-2873 3283);
DISPLAY 0.617021 (-2873 3283);
PAINT GREEN (-2873 3283);
FORCEPROP 2 LAST CDS_LIB mstr_standard
J 0
(-2875 3275);
PAINT MONO (-2875 3275);
DISPLAY INVISIBLE (-2875 3275);
FORCEPROP 1 LAST BODY_TYPE PLUMBING
J 2
(-2875 3225);
DISPLAY 1.595745 (-2875 3225);
PAINT GREEN (-2875 3225);
DISPLAY INVISIBLE (-2875 3225);
FORCEPROP 1 LAST HDL_TAP TRUE
J 2
(-3200 3150);
DISPLAY 1.595745 (-3200 3150);
PAINT GREEN (-3200 3150);
DISPLAY INVISIBLE (-3200 3150);
FORCEPROP 1 LAST PATH I133
J 2
(-2873 3275);
DISPLAY 0.872340 (-2873 3275);
PAINT GREEN (-2873 3275);
DISPLAY INVISIBLE (-2873 3275);
FORCEADD TAP..6
R 2
(-2875 3325);
FORCEPROP 3 LASTPIN (-2925 3325) SIG_NAME M_H_DQS_DN<9>
J 0
(-2915 3335);
DISPLAY 0.659574 (-2915 3335);
PAINT MONO (-2915 3335);
DISPLAY INVISIBLE (-2915 3335);
FORCEPROP 1 LASTPIN (-2925 3325) BN 9
J 2
(-2873 3333);
DISPLAY 0.617021 (-2873 3333);
PAINT GREEN (-2873 3333);
FORCEPROP 2 LAST CDS_LIB mstr_standard
J 0
(-2875 3325);
PAINT MONO (-2875 3325);
DISPLAY INVISIBLE (-2875 3325);
FORCEPROP 1 LAST BODY_TYPE PLUMBING
J 2
(-2875 3275);
DISPLAY 1.595745 (-2875 3275);
PAINT GREEN (-2875 3275);
DISPLAY INVISIBLE (-2875 3275);
FORCEPROP 1 LAST HDL_TAP TRUE
J 2
(-3200 3200);
DISPLAY 1.595745 (-3200 3200);
PAINT GREEN (-3200 3200);
DISPLAY INVISIBLE (-3200 3200);
FORCEPROP 1 LAST PATH I134
J 2
(-2873 3325);
DISPLAY 0.872340 (-2873 3325);
PAINT GREEN (-2873 3325);
DISPLAY INVISIBLE (-2873 3325);
FORCEADD TAP..6
R 2
(-2875 3375);
FORCEPROP 3 LASTPIN (-2925 3375) SIG_NAME M_H_DQS_DN<10>
J 0
(-2915 3385);
DISPLAY 0.659574 (-2915 3385);
PAINT MONO (-2915 3385);
DISPLAY INVISIBLE (-2915 3385);
FORCEPROP 1 LASTPIN (-2925 3375) BN 10
J 2
(-2873 3383);
DISPLAY 0.617021 (-2873 3383);
PAINT GREEN (-2873 3383);
FORCEPROP 2 LAST CDS_LIB mstr_standard
J 0
(-2875 3375);
PAINT MONO (-2875 3375);
DISPLAY INVISIBLE (-2875 3375);
FORCEPROP 1 LAST BODY_TYPE PLUMBING
J 2
(-2875 3325);
DISPLAY 1.595745 (-2875 3325);
PAINT GREEN (-2875 3325);
DISPLAY INVISIBLE (-2875 3325);
FORCEPROP 1 LAST HDL_TAP TRUE
J 2
(-3200 3250);
DISPLAY 1.595745 (-3200 3250);
PAINT GREEN (-3200 3250);
DISPLAY INVISIBLE (-3200 3250);
FORCEPROP 1 LAST PATH I135
J 2
(-2873 3375);
DISPLAY 0.872340 (-2873 3375);
PAINT GREEN (-2873 3375);
DISPLAY INVISIBLE (-2873 3375);
FORCEADD TAP..6
R 2
(-2875 3475);
FORCEPROP 3 LASTPIN (-2925 3475) SIG_NAME M_H_DQS_DN<12>
J 0
(-2915 3485);
DISPLAY 0.659574 (-2915 3485);
PAINT MONO (-2915 3485);
DISPLAY INVISIBLE (-2915 3485);
FORCEPROP 1 LASTPIN (-2925 3475) BN 12
J 2
(-2873 3483);
DISPLAY 0.617021 (-2873 3483);
PAINT GREEN (-2873 3483);
FORCEPROP 2 LAST CDS_LIB mstr_standard
J 0
(-2875 3475);
PAINT MONO (-2875 3475);
DISPLAY INVISIBLE (-2875 3475);
FORCEPROP 1 LAST BODY_TYPE PLUMBING
J 2
(-2875 3425);
DISPLAY 1.595745 (-2875 3425);
PAINT GREEN (-2875 3425);
DISPLAY INVISIBLE (-2875 3425);
FORCEPROP 1 LAST HDL_TAP TRUE
J 2
(-3200 3350);
DISPLAY 1.595745 (-3200 3350);
PAINT GREEN (-3200 3350);
DISPLAY INVISIBLE (-3200 3350);
FORCEPROP 1 LAST PATH I136
J 2
(-2873 3475);
DISPLAY 0.872340 (-2873 3475);
PAINT GREEN (-2873 3475);
DISPLAY INVISIBLE (-2873 3475);
FORCEADD TAP..6
R 2
(-2875 3425);
FORCEPROP 3 LASTPIN (-2925 3425) SIG_NAME M_H_DQS_DN<11>
J 0
(-2915 3435);
DISPLAY 0.659574 (-2915 3435);
PAINT MONO (-2915 3435);
DISPLAY INVISIBLE (-2915 3435);
FORCEPROP 1 LASTPIN (-2925 3425) BN 11
J 2
(-2873 3433);
DISPLAY 0.617021 (-2873 3433);
PAINT GREEN (-2873 3433);
FORCEPROP 2 LAST CDS_LIB mstr_standard
J 0
(-2875 3425);
PAINT MONO (-2875 3425);
DISPLAY INVISIBLE (-2875 3425);
FORCEPROP 1 LAST BODY_TYPE PLUMBING
J 2
(-2875 3375);
DISPLAY 1.595745 (-2875 3375);
PAINT GREEN (-2875 3375);
DISPLAY INVISIBLE (-2875 3375);
FORCEPROP 1 LAST HDL_TAP TRUE
J 2
(-3200 3300);
DISPLAY 1.595745 (-3200 3300);
PAINT GREEN (-3200 3300);
DISPLAY INVISIBLE (-3200 3300);
FORCEPROP 1 LAST PATH I137
J 2
(-2873 3425);
DISPLAY 0.872340 (-2873 3425);
PAINT GREEN (-2873 3425);
DISPLAY INVISIBLE (-2873 3425);
FORCEADD TAP..6
R 2
(-2875 3625);
FORCEPROP 3 LASTPIN (-2925 3625) SIG_NAME M_H_DQS_DN<15>
J 0
(-2915 3635);
DISPLAY 0.659574 (-2915 3635);
PAINT MONO (-2915 3635);
DISPLAY INVISIBLE (-2915 3635);
FORCEPROP 1 LASTPIN (-2925 3625) BN 15
J 2
(-2873 3633);
DISPLAY 0.617021 (-2873 3633);
PAINT GREEN (-2873 3633);
FORCEPROP 2 LAST CDS_LIB mstr_standard
J 0
(-2875 3625);
PAINT MONO (-2875 3625);
DISPLAY INVISIBLE (-2875 3625);
FORCEPROP 1 LAST BODY_TYPE PLUMBING
J 2
(-2875 3575);
DISPLAY 1.595745 (-2875 3575);
PAINT GREEN (-2875 3575);
DISPLAY INVISIBLE (-2875 3575);
FORCEPROP 1 LAST HDL_TAP TRUE
J 2
(-3200 3500);
DISPLAY 1.595745 (-3200 3500);
PAINT GREEN (-3200 3500);
DISPLAY INVISIBLE (-3200 3500);
FORCEPROP 1 LAST PATH I138
J 2
(-2873 3625);
DISPLAY 0.872340 (-2873 3625);
PAINT GREEN (-2873 3625);
DISPLAY INVISIBLE (-2873 3625);
FORCEADD TAP..6
R 2
(-2875 3575);
FORCEPROP 3 LASTPIN (-2925 3575) SIG_NAME M_H_DQS_DN<14>
J 0
(-2915 3585);
DISPLAY 0.659574 (-2915 3585);
PAINT MONO (-2915 3585);
DISPLAY INVISIBLE (-2915 3585);
FORCEPROP 1 LASTPIN (-2925 3575) BN 14
J 2
(-2873 3583);
DISPLAY 0.617021 (-2873 3583);
PAINT GREEN (-2873 3583);
FORCEPROP 2 LAST CDS_LIB mstr_standard
J 0
(-2875 3575);
PAINT MONO (-2875 3575);
DISPLAY INVISIBLE (-2875 3575);
FORCEPROP 1 LAST BODY_TYPE PLUMBING
J 2
(-2875 3525);
DISPLAY 1.595745 (-2875 3525);
PAINT GREEN (-2875 3525);
DISPLAY INVISIBLE (-2875 3525);
FORCEPROP 1 LAST HDL_TAP TRUE
J 2
(-3200 3450);
DISPLAY 1.595745 (-3200 3450);
PAINT GREEN (-3200 3450);
DISPLAY INVISIBLE (-3200 3450);
FORCEPROP 1 LAST PATH I139
J 2
(-2873 3575);
DISPLAY 0.872340 (-2873 3575);
PAINT GREEN (-2873 3575);
DISPLAY INVISIBLE (-2873 3575);
FORCEADD TAP..6
(-5600 1125);
FORCEPROP 3 LASTPIN (-5550 1125) SIG_NAME M_H_ECC<1>
J 0
(-5540 1135);
DISPLAY 0.659574 (-5540 1135);
PAINT MONO (-5540 1135);
DISPLAY INVISIBLE (-5540 1135);
FORCEPROP 1 LASTPIN (-5550 1125) BN 1
J 0
(-5602 1133);
DISPLAY 0.617021 (-5602 1133);
PAINT GREEN (-5602 1133);
FORCEPROP 2 LAST CDS_LIB mstr_standard
J 0
(-5600 1125);
PAINT MONO (-5600 1125);
DISPLAY INVISIBLE (-5600 1125);
FORCEPROP 1 LAST BODY_TYPE PLUMBING
J 0
(-5600 1075);
DISPLAY 1.595745 (-5600 1075);
PAINT GREEN (-5600 1075);
DISPLAY INVISIBLE (-5600 1075);
FORCEPROP 1 LAST HDL_TAP TRUE
J 0
(-5275 1000);
DISPLAY 1.595745 (-5275 1000);
PAINT GREEN (-5275 1000);
DISPLAY INVISIBLE (-5275 1000);
FORCEPROP 1 LAST PATH I14
J 0
(-5602 1125);
DISPLAY 0.872340 (-5602 1125);
PAINT GREEN (-5602 1125);
DISPLAY INVISIBLE (-5602 1125);
FORCEADD TAP..6
R 2
(-2875 3525);
FORCEPROP 3 LASTPIN (-2925 3525) SIG_NAME M_H_DQS_DN<13>
J 0
(-2915 3535);
DISPLAY 0.659574 (-2915 3535);
PAINT MONO (-2915 3535);
DISPLAY INVISIBLE (-2915 3535);
FORCEPROP 1 LASTPIN (-2925 3525) BN 13
J 2
(-2873 3533);
DISPLAY 0.617021 (-2873 3533);
PAINT GREEN (-2873 3533);
FORCEPROP 2 LAST CDS_LIB mstr_standard
J 0
(-2875 3525);
PAINT MONO (-2875 3525);
DISPLAY INVISIBLE (-2875 3525);
FORCEPROP 1 LAST BODY_TYPE PLUMBING
J 2
(-2875 3475);
DISPLAY 1.595745 (-2875 3475);
PAINT GREEN (-2875 3475);
DISPLAY INVISIBLE (-2875 3475);
FORCEPROP 1 LAST HDL_TAP TRUE
J 2
(-3200 3400);
DISPLAY 1.595745 (-3200 3400);
PAINT GREEN (-3200 3400);
DISPLAY INVISIBLE (-3200 3400);
FORCEPROP 1 LAST PATH I140
J 2
(-2873 3525);
DISPLAY 0.872340 (-2873 3525);
PAINT GREEN (-2873 3525);
DISPLAY INVISIBLE (-2873 3525);
FORCEADD TAP..6
R 2
(-2875 3675);
FORCEPROP 3 LASTPIN (-2925 3675) SIG_NAME M_H_DQS_DN<16>
J 0
(-2915 3685);
DISPLAY 0.659574 (-2915 3685);
PAINT MONO (-2915 3685);
DISPLAY INVISIBLE (-2915 3685);
FORCEPROP 1 LASTPIN (-2925 3675) BN 16
J 2
(-2873 3683);
DISPLAY 0.617021 (-2873 3683);
PAINT GREEN (-2873 3683);
FORCEPROP 2 LAST CDS_LIB mstr_standard
J 0
(-2875 3675);
PAINT MONO (-2875 3675);
DISPLAY INVISIBLE (-2875 3675);
FORCEPROP 1 LAST BODY_TYPE PLUMBING
J 2
(-2875 3625);
DISPLAY 1.595745 (-2875 3625);
PAINT GREEN (-2875 3625);
DISPLAY INVISIBLE (-2875 3625);
FORCEPROP 1 LAST HDL_TAP TRUE
J 2
(-3200 3550);
DISPLAY 1.595745 (-3200 3550);
PAINT GREEN (-3200 3550);
DISPLAY INVISIBLE (-3200 3550);
FORCEPROP 1 LAST PATH I141
J 2
(-2873 3675);
DISPLAY 0.872340 (-2873 3675);
PAINT GREEN (-2873 3675);
DISPLAY INVISIBLE (-2873 3675);
FORCEADD TAP..6
R 2
(-2875 3725);
FORCEPROP 3 LASTPIN (-2925 3725) SIG_NAME M_H_DQS_DN<17>
J 0
(-2915 3735);
DISPLAY 0.659574 (-2915 3735);
PAINT MONO (-2915 3735);
DISPLAY INVISIBLE (-2915 3735);
FORCEPROP 1 LASTPIN (-2925 3725) BN 17
J 2
(-2873 3733);
DISPLAY 0.617021 (-2873 3733);
PAINT GREEN (-2873 3733);
FORCEPROP 2 LAST CDS_LIB mstr_standard
J 0
(-2875 3725);
PAINT MONO (-2875 3725);
DISPLAY INVISIBLE (-2875 3725);
FORCEPROP 1 LAST BODY_TYPE PLUMBING
J 2
(-2875 3675);
DISPLAY 1.595745 (-2875 3675);
PAINT GREEN (-2875 3675);
DISPLAY INVISIBLE (-2875 3675);
FORCEPROP 1 LAST HDL_TAP TRUE
J 2
(-3200 3600);
DISPLAY 1.595745 (-3200 3600);
PAINT GREEN (-3200 3600);
DISPLAY INVISIBLE (-3200 3600);
FORCEPROP 1 LAST PATH I142
J 2
(-2873 3725);
DISPLAY 0.872340 (-2873 3725);
PAINT GREEN (-2873 3725);
DISPLAY INVISIBLE (-2873 3725);
FORCEADD TAP..6
R 2
(-2875 3825);
FORCEPROP 3 LASTPIN (-2925 3825) SIG_NAME M_H_DQS_DP<0>
J 0
(-2915 3835);
DISPLAY 0.659574 (-2915 3835);
PAINT MONO (-2915 3835);
DISPLAY INVISIBLE (-2915 3835);
FORCEPROP 1 LASTPIN (-2925 3825) BN 0
J 2
(-2873 3833);
DISPLAY 0.617021 (-2873 3833);
PAINT GREEN (-2873 3833);
FORCEPROP 2 LAST CDS_LIB mstr_standard
J 0
(-2875 3825);
PAINT MONO (-2875 3825);
DISPLAY INVISIBLE (-2875 3825);
FORCEPROP 1 LAST BODY_TYPE PLUMBING
J 2
(-2875 3775);
DISPLAY 1.595745 (-2875 3775);
PAINT GREEN (-2875 3775);
DISPLAY INVISIBLE (-2875 3775);
FORCEPROP 1 LAST HDL_TAP TRUE
J 2
(-3200 3700);
DISPLAY 1.595745 (-3200 3700);
PAINT GREEN (-3200 3700);
DISPLAY INVISIBLE (-3200 3700);
FORCEPROP 1 LAST PATH I143
J 2
(-2873 3825);
DISPLAY 0.872340 (-2873 3825);
PAINT GREEN (-2873 3825);
DISPLAY INVISIBLE (-2873 3825);
FORCEADD TAP..6
R 2
(-2875 3875);
FORCEPROP 3 LASTPIN (-2925 3875) SIG_NAME M_H_DQS_DP<1>
J 0
(-2915 3885);
DISPLAY 0.659574 (-2915 3885);
PAINT MONO (-2915 3885);
DISPLAY INVISIBLE (-2915 3885);
FORCEPROP 1 LASTPIN (-2925 3875) BN 1
J 2
(-2873 3883);
DISPLAY 0.617021 (-2873 3883);
PAINT GREEN (-2873 3883);
FORCEPROP 2 LAST CDS_LIB mstr_standard
J 0
(-2875 3875);
PAINT MONO (-2875 3875);
DISPLAY INVISIBLE (-2875 3875);
FORCEPROP 1 LAST BODY_TYPE PLUMBING
J 2
(-2875 3825);
DISPLAY 1.595745 (-2875 3825);
PAINT GREEN (-2875 3825);
DISPLAY INVISIBLE (-2875 3825);
FORCEPROP 1 LAST HDL_TAP TRUE
J 2
(-3200 3750);
DISPLAY 1.595745 (-3200 3750);
PAINT GREEN (-3200 3750);
DISPLAY INVISIBLE (-3200 3750);
FORCEPROP 1 LAST PATH I144
J 2
(-2873 3875);
DISPLAY 0.872340 (-2873 3875);
PAINT GREEN (-2873 3875);
DISPLAY INVISIBLE (-2873 3875);
FORCEADD TAP..6
R 2
(-2875 3925);
FORCEPROP 3 LASTPIN (-2925 3925) SIG_NAME M_H_DQS_DP<2>
J 0
(-2915 3935);
DISPLAY 0.659574 (-2915 3935);
PAINT MONO (-2915 3935);
DISPLAY INVISIBLE (-2915 3935);
FORCEPROP 1 LASTPIN (-2925 3925) BN 2
J 2
(-2873 3933);
DISPLAY 0.617021 (-2873 3933);
PAINT GREEN (-2873 3933);
FORCEPROP 2 LAST CDS_LIB mstr_standard
J 0
(-2875 3925);
PAINT MONO (-2875 3925);
DISPLAY INVISIBLE (-2875 3925);
FORCEPROP 1 LAST BODY_TYPE PLUMBING
J 2
(-2875 3875);
DISPLAY 1.595745 (-2875 3875);
PAINT GREEN (-2875 3875);
DISPLAY INVISIBLE (-2875 3875);
FORCEPROP 1 LAST HDL_TAP TRUE
J 2
(-3200 3800);
DISPLAY 1.595745 (-3200 3800);
PAINT GREEN (-3200 3800);
DISPLAY INVISIBLE (-3200 3800);
FORCEPROP 1 LAST PATH I145
J 2
(-2873 3925);
DISPLAY 0.872340 (-2873 3925);
PAINT GREEN (-2873 3925);
DISPLAY INVISIBLE (-2873 3925);
FORCEADD TAP..6
R 2
(-2875 3975);
FORCEPROP 3 LASTPIN (-2925 3975) SIG_NAME M_H_DQS_DP<3>
J 0
(-2915 3985);
DISPLAY 0.659574 (-2915 3985);
PAINT MONO (-2915 3985);
DISPLAY INVISIBLE (-2915 3985);
FORCEPROP 1 LASTPIN (-2925 3975) BN 3
J 2
(-2873 3983);
DISPLAY 0.617021 (-2873 3983);
PAINT GREEN (-2873 3983);
FORCEPROP 2 LAST CDS_LIB mstr_standard
J 0
(-2875 3975);
PAINT MONO (-2875 3975);
DISPLAY INVISIBLE (-2875 3975);
FORCEPROP 1 LAST BODY_TYPE PLUMBING
J 2
(-2875 3925);
DISPLAY 1.595745 (-2875 3925);
PAINT GREEN (-2875 3925);
DISPLAY INVISIBLE (-2875 3925);
FORCEPROP 1 LAST HDL_TAP TRUE
J 2
(-3200 3850);
DISPLAY 1.595745 (-3200 3850);
PAINT GREEN (-3200 3850);
DISPLAY INVISIBLE (-3200 3850);
FORCEPROP 1 LAST PATH I146
J 2
(-2873 3975);
DISPLAY 0.872340 (-2873 3975);
PAINT GREEN (-2873 3975);
DISPLAY INVISIBLE (-2873 3975);
FORCEADD OFFPAGE..2
(-2025 525);
FORCEPROP 2 LAST $XR1 80 
J 0
(-1746 525);
DISPLAY 0.638298 (-1746 525);
PAINT MONO (-1746 525);
FORCEPROP 2 LAST $XR0 79 
J 0
(-1836 525);
DISPLAY 0.638298 (-1836 525);
PAINT MONO (-1836 525);
FORCEPROP 2 LAST CDS_LIB mstr_standard
J 0
(-2025 525);
PAINT MONO (-2025 525);
DISPLAY INVISIBLE (-2025 525);
FORCEPROP 1 LAST OFFPAGE TRUE
J 0
(-1700 400);
DISPLAY 1.170213 (-1700 400);
PAINT GREEN (-1700 400);
DISPLAY INVISIBLE (-1700 400);
FORCEPROP 1 LAST COMMENT_BODY TRUE
J 0
(-2070 430);
DISPLAY 1.170213 (-2070 430);
PAINT GREEN (-2070 430);
DISPLAY INVISIBLE (-2070 430);
FORCEPROP 2 LAST PATH I147
J 0
(-1850 600);
DISPLAY 1.021277 (-1850 600);
PAINT ORANGE (-1850 600);
DISPLAY INVISIBLE (-1850 600);
FORCEADD OFFPAGE..4
(-2025 575);
FORCEPROP 2 LAST $XR1 80 
J 0
(-1749 575);
DISPLAY 0.638298 (-1749 575);
PAINT MONO (-1749 575);
FORCEPROP 2 LAST $XR0 79 
J 0
(-1839 575);
DISPLAY 0.638298 (-1839 575);
PAINT MONO (-1839 575);
FORCEPROP 2 LAST CDS_LIB mstr_standard
J 0
(-2025 575);
PAINT MONO (-2025 575);
DISPLAY INVISIBLE (-2025 575);
FORCEPROP 1 LAST OFFPAGE TRUE
J 0
(-1700 450);
DISPLAY 1.170213 (-1700 450);
PAINT GREEN (-1700 450);
DISPLAY INVISIBLE (-1700 450);
FORCEPROP 1 LAST COMMENT_BODY TRUE
J 0
(-2050 475);
DISPLAY 1.170213 (-2050 475);
PAINT GREEN (-2050 475);
DISPLAY INVISIBLE (-2050 475);
FORCEPROP 2 LAST PATH I148
J 0
(-1850 650);
DISPLAY 1.021277 (-1850 650);
PAINT ORANGE (-1850 650);
DISPLAY INVISIBLE (-1850 650);
FORCEADD OFFPAGE..2
(-2025 625);
FORCEPROP 2 LAST $XR1 80 
J 0
(-1746 625);
DISPLAY 0.638298 (-1746 625);
PAINT MONO (-1746 625);
FORCEPROP 2 LAST $XR0 79 
J 0
(-1836 625);
DISPLAY 0.638298 (-1836 625);
PAINT MONO (-1836 625);
FORCEPROP 2 LAST CDS_LIB mstr_standard
J 0
(-2025 625);
PAINT MONO (-2025 625);
DISPLAY INVISIBLE (-2025 625);
FORCEPROP 1 LAST OFFPAGE TRUE
J 0
(-1700 500);
DISPLAY 1.170213 (-1700 500);
PAINT GREEN (-1700 500);
DISPLAY INVISIBLE (-1700 500);
FORCEPROP 1 LAST COMMENT_BODY TRUE
J 0
(-2070 530);
DISPLAY 1.170213 (-2070 530);
PAINT GREEN (-2070 530);
DISPLAY INVISIBLE (-2070 530);
FORCEPROP 2 LAST PATH I149
J 0
(-1850 700);
DISPLAY 1.021277 (-1850 700);
PAINT ORANGE (-1850 700);
DISPLAY INVISIBLE (-1850 700);
FORCEADD TAP..6
(-5600 1175);
FORCEPROP 3 LASTPIN (-5550 1175) SIG_NAME M_H_ECC<2>
J 0
(-5540 1185);
DISPLAY 0.659574 (-5540 1185);
PAINT MONO (-5540 1185);
DISPLAY INVISIBLE (-5540 1185);
FORCEPROP 1 LASTPIN (-5550 1175) BN 2
J 0
(-5602 1183);
DISPLAY 0.617021 (-5602 1183);
PAINT GREEN (-5602 1183);
FORCEPROP 2 LAST CDS_LIB mstr_standard
J 0
(-5600 1175);
PAINT MONO (-5600 1175);
DISPLAY INVISIBLE (-5600 1175);
FORCEPROP 1 LAST BODY_TYPE PLUMBING
J 0
(-5600 1125);
DISPLAY 1.595745 (-5600 1125);
PAINT GREEN (-5600 1125);
DISPLAY INVISIBLE (-5600 1125);
FORCEPROP 1 LAST HDL_TAP TRUE
J 0
(-5275 1050);
DISPLAY 1.595745 (-5275 1050);
PAINT GREEN (-5275 1050);
DISPLAY INVISIBLE (-5275 1050);
FORCEPROP 1 LAST PATH I15
J 0
(-5602 1175);
DISPLAY 0.872340 (-5602 1175);
PAINT GREEN (-5602 1175);
DISPLAY INVISIBLE (-5602 1175);
FORCEADD OFFPAGE..2
(-2025 825);
FORCEPROP 2 LAST $XR1 80 
J 0
(-1746 825);
DISPLAY 0.638298 (-1746 825);
PAINT MONO (-1746 825);
FORCEPROP 2 LAST $XR0 79 
J 0
(-1836 825);
DISPLAY 0.638298 (-1836 825);
PAINT MONO (-1836 825);
FORCEPROP 2 LAST CDS_LIB mstr_standard
J 0
(-2025 825);
PAINT MONO (-2025 825);
DISPLAY INVISIBLE (-2025 825);
FORCEPROP 1 LAST OFFPAGE TRUE
J 0
(-1700 700);
DISPLAY 1.170213 (-1700 700);
PAINT GREEN (-1700 700);
DISPLAY INVISIBLE (-1700 700);
FORCEPROP 1 LAST COMMENT_BODY TRUE
J 0
(-2070 730);
DISPLAY 1.170213 (-2070 730);
PAINT GREEN (-2070 730);
DISPLAY INVISIBLE (-2070 730);
FORCEPROP 2 LAST PATH I150
J 0
(-1850 900);
DISPLAY 1.021277 (-1850 900);
PAINT ORANGE (-1850 900);
DISPLAY INVISIBLE (-1850 900);
FORCEADD OFFPAGE..2
(-2025 925);
FORCEPROP 2 LAST $XR1 80 
J 0
(-1746 925);
DISPLAY 0.638298 (-1746 925);
PAINT MONO (-1746 925);
FORCEPROP 2 LAST $XR0 79 
J 0
(-1836 925);
DISPLAY 0.638298 (-1836 925);
PAINT MONO (-1836 925);
FORCEPROP 2 LAST CDS_LIB mstr_standard
J 0
(-2025 925);
PAINT MONO (-2025 925);
DISPLAY INVISIBLE (-2025 925);
FORCEPROP 1 LAST OFFPAGE TRUE
J 0
(-1700 800);
DISPLAY 1.170213 (-1700 800);
PAINT GREEN (-1700 800);
DISPLAY INVISIBLE (-1700 800);
FORCEPROP 1 LAST COMMENT_BODY TRUE
J 0
(-2070 830);
DISPLAY 1.170213 (-2070 830);
PAINT GREEN (-2070 830);
DISPLAY INVISIBLE (-2070 830);
FORCEPROP 2 LAST PATH I151
J 0
(-1850 1000);
DISPLAY 1.021277 (-1850 1000);
PAINT ORANGE (-1850 1000);
DISPLAY INVISIBLE (-1850 1000);
FORCEADD OFFPAGE..2
(-2025 1375);
FORCEPROP 2 LAST $XR1 80 
J 0
(-1746 1375);
DISPLAY 0.638298 (-1746 1375);
PAINT MONO (-1746 1375);
FORCEPROP 2 LAST $XR0 79 
J 0
(-1836 1375);
DISPLAY 0.638298 (-1836 1375);
PAINT MONO (-1836 1375);
FORCEPROP 2 LAST CDS_LIB mstr_standard
J 0
(-2025 1375);
PAINT MONO (-2025 1375);
DISPLAY INVISIBLE (-2025 1375);
FORCEPROP 1 LAST OFFPAGE TRUE
J 0
(-1700 1250);
DISPLAY 1.170213 (-1700 1250);
PAINT GREEN (-1700 1250);
DISPLAY INVISIBLE (-1700 1250);
FORCEPROP 1 LAST COMMENT_BODY TRUE
J 0
(-2070 1280);
DISPLAY 1.170213 (-2070 1280);
PAINT GREEN (-2070 1280);
DISPLAY INVISIBLE (-2070 1280);
FORCEPROP 2 LAST PATH I152
J 0
(-1850 1450);
DISPLAY 1.021277 (-1850 1450);
PAINT ORANGE (-1850 1450);
DISPLAY INVISIBLE (-1850 1450);
FORCEADD OFFPAGE..2
(-2025 1625);
FORCEPROP 2 LAST $XR1 80 
J 0
(-1746 1625);
DISPLAY 0.638298 (-1746 1625);
PAINT MONO (-1746 1625);
FORCEPROP 2 LAST $XR0 79 
J 0
(-1836 1625);
DISPLAY 0.638298 (-1836 1625);
PAINT MONO (-1836 1625);
FORCEPROP 2 LAST CDS_LIB mstr_standard
J 0
(-2025 1625);
PAINT MONO (-2025 1625);
DISPLAY INVISIBLE (-2025 1625);
FORCEPROP 1 LAST OFFPAGE TRUE
J 0
(-1700 1500);
DISPLAY 1.170213 (-1700 1500);
PAINT GREEN (-1700 1500);
DISPLAY INVISIBLE (-1700 1500);
FORCEPROP 1 LAST COMMENT_BODY TRUE
J 0
(-2070 1530);
DISPLAY 1.170213 (-2070 1530);
PAINT GREEN (-2070 1530);
DISPLAY INVISIBLE (-2070 1530);
FORCEPROP 2 LAST PATH I153
J 0
(-1850 1700);
DISPLAY 1.021277 (-1850 1700);
PAINT ORANGE (-1850 1700);
DISPLAY INVISIBLE (-1850 1700);
FORCEADD OFFPAGE..2
(-2025 1875);
FORCEPROP 2 LAST $XR1 80 
J 0
(-1746 1875);
DISPLAY 0.638298 (-1746 1875);
PAINT MONO (-1746 1875);
FORCEPROP 2 LAST $XR0 79 
J 0
(-1836 1875);
DISPLAY 0.638298 (-1836 1875);
PAINT MONO (-1836 1875);
FORCEPROP 2 LAST CDS_LIB mstr_standard
J 0
(-2025 1875);
PAINT MONO (-2025 1875);
DISPLAY INVISIBLE (-2025 1875);
FORCEPROP 1 LAST OFFPAGE TRUE
J 0
(-1700 1750);
DISPLAY 1.170213 (-1700 1750);
PAINT GREEN (-1700 1750);
DISPLAY INVISIBLE (-1700 1750);
FORCEPROP 1 LAST COMMENT_BODY TRUE
J 0
(-2070 1780);
DISPLAY 1.170213 (-2070 1780);
PAINT GREEN (-2070 1780);
DISPLAY INVISIBLE (-2070 1780);
FORCEPROP 2 LAST PATH I154
J 0
(-1850 1950);
DISPLAY 1.021277 (-1850 1950);
PAINT ORANGE (-1850 1950);
DISPLAY INVISIBLE (-1850 1950);
FORCEADD OFFPAGE..2
(-2025 2825);
FORCEPROP 2 LAST $XR1 80 
J 0
(-1746 2825);
DISPLAY 0.638298 (-1746 2825);
PAINT MONO (-1746 2825);
FORCEPROP 2 LAST $XR0 79 
J 0
(-1836 2825);
DISPLAY 0.638298 (-1836 2825);
PAINT MONO (-1836 2825);
FORCEPROP 2 LAST CDS_LIB mstr_standard
J 0
(-2025 2825);
PAINT MONO (-2025 2825);
DISPLAY INVISIBLE (-2025 2825);
FORCEPROP 1 LAST OFFPAGE TRUE
J 0
(-1700 2700);
DISPLAY 1.170213 (-1700 2700);
PAINT GREEN (-1700 2700);
DISPLAY INVISIBLE (-1700 2700);
FORCEPROP 1 LAST COMMENT_BODY TRUE
J 0
(-2070 2730);
DISPLAY 1.170213 (-2070 2730);
PAINT GREEN (-2070 2730);
DISPLAY INVISIBLE (-2070 2730);
FORCEPROP 2 LAST PATH I155
J 0
(-1850 2900);
DISPLAY 1.021277 (-1850 2900);
PAINT ORANGE (-1850 2900);
DISPLAY INVISIBLE (-1850 2900);
FORCEADD OFFPAGE..3
(-2025 3775);
FORCEPROP 2 LAST $XR1 80 
J 0
(-1721 3775);
DISPLAY 0.638298 (-1721 3775);
PAINT MONO (-1721 3775);
FORCEPROP 2 LAST $XR0 79 
J 0
(-1811 3775);
DISPLAY 0.638298 (-1811 3775);
PAINT MONO (-1811 3775);
FORCEPROP 2 LAST CDS_LIB mstr_standard
J 0
(-2025 3775);
PAINT MONO (-2025 3775);
DISPLAY INVISIBLE (-2025 3775);
FORCEPROP 1 LAST OFFPAGE TRUE
J 0
(-1700 3650);
DISPLAY 1.170213 (-1700 3650);
PAINT GREEN (-1700 3650);
DISPLAY INVISIBLE (-1700 3650);
FORCEPROP 1 LAST COMMENT_BODY TRUE
J 0
(-2075 3675);
DISPLAY 1.170213 (-2075 3675);
PAINT GREEN (-2075 3675);
DISPLAY INVISIBLE (-2075 3675);
FORCEPROP 2 LAST PATH I156
J 0
(-1825 3850);
DISPLAY 1.021277 (-1825 3850);
PAINT ORANGE (-1825 3850);
DISPLAY INVISIBLE (-1825 3850);
FORCEADD TAP..6
R 2
(-2875 4025);
FORCEPROP 3 LASTPIN (-2925 4025) SIG_NAME M_H_DQS_DP<4>
J 0
(-2915 4035);
DISPLAY 0.659574 (-2915 4035);
PAINT MONO (-2915 4035);
DISPLAY INVISIBLE (-2915 4035);
FORCEPROP 1 LASTPIN (-2925 4025) BN 4
J 2
(-2873 4033);
DISPLAY 0.617021 (-2873 4033);
PAINT GREEN (-2873 4033);
FORCEPROP 2 LAST CDS_LIB mstr_standard
J 0
(-2875 4025);
PAINT MONO (-2875 4025);
DISPLAY INVISIBLE (-2875 4025);
FORCEPROP 1 LAST BODY_TYPE PLUMBING
J 2
(-2875 3975);
DISPLAY 1.595745 (-2875 3975);
PAINT GREEN (-2875 3975);
DISPLAY INVISIBLE (-2875 3975);
FORCEPROP 1 LAST HDL_TAP TRUE
J 2
(-3200 3900);
DISPLAY 1.595745 (-3200 3900);
PAINT GREEN (-3200 3900);
DISPLAY INVISIBLE (-3200 3900);
FORCEPROP 1 LAST PATH I157
J 2
(-2873 4025);
DISPLAY 0.872340 (-2873 4025);
PAINT GREEN (-2873 4025);
DISPLAY INVISIBLE (-2873 4025);
FORCEADD TAP..6
R 2
(-2875 4125);
FORCEPROP 3 LASTPIN (-2925 4125) SIG_NAME M_H_DQS_DP<6>
J 0
(-2915 4135);
DISPLAY 0.659574 (-2915 4135);
PAINT MONO (-2915 4135);
DISPLAY INVISIBLE (-2915 4135);
FORCEPROP 1 LASTPIN (-2925 4125) BN 6
J 2
(-2873 4133);
DISPLAY 0.617021 (-2873 4133);
PAINT GREEN (-2873 4133);
FORCEPROP 2 LAST CDS_LIB mstr_standard
J 0
(-2875 4125);
PAINT MONO (-2875 4125);
DISPLAY INVISIBLE (-2875 4125);
FORCEPROP 1 LAST BODY_TYPE PLUMBING
J 2
(-2875 4075);
DISPLAY 1.595745 (-2875 4075);
PAINT GREEN (-2875 4075);
DISPLAY INVISIBLE (-2875 4075);
FORCEPROP 1 LAST HDL_TAP TRUE
J 2
(-3200 4000);
DISPLAY 1.595745 (-3200 4000);
PAINT GREEN (-3200 4000);
DISPLAY INVISIBLE (-3200 4000);
FORCEPROP 1 LAST PATH I158
J 2
(-2873 4125);
DISPLAY 0.872340 (-2873 4125);
PAINT GREEN (-2873 4125);
DISPLAY INVISIBLE (-2873 4125);
FORCEADD TAP..6
R 2
(-2875 4075);
FORCEPROP 3 LASTPIN (-2925 4075) SIG_NAME M_H_DQS_DP<5>
J 0
(-2915 4085);
DISPLAY 0.659574 (-2915 4085);
PAINT MONO (-2915 4085);
DISPLAY INVISIBLE (-2915 4085);
FORCEPROP 1 LASTPIN (-2925 4075) BN 5
J 2
(-2873 4083);
DISPLAY 0.617021 (-2873 4083);
PAINT GREEN (-2873 4083);
FORCEPROP 2 LAST CDS_LIB mstr_standard
J 0
(-2875 4075);
PAINT MONO (-2875 4075);
DISPLAY INVISIBLE (-2875 4075);
FORCEPROP 1 LAST BODY_TYPE PLUMBING
J 2
(-2875 4025);
DISPLAY 1.595745 (-2875 4025);
PAINT GREEN (-2875 4025);
DISPLAY INVISIBLE (-2875 4025);
FORCEPROP 1 LAST HDL_TAP TRUE
J 2
(-3200 3950);
DISPLAY 1.595745 (-3200 3950);
PAINT GREEN (-3200 3950);
DISPLAY INVISIBLE (-3200 3950);
FORCEPROP 1 LAST PATH I159
J 2
(-2873 4075);
DISPLAY 0.872340 (-2873 4075);
PAINT GREEN (-2873 4075);
DISPLAY INVISIBLE (-2873 4075);
FORCEADD TAP..6
(-5600 1275);
FORCEPROP 3 LASTPIN (-5550 1275) SIG_NAME M_H_ECC<4>
J 0
(-5540 1285);
DISPLAY 0.659574 (-5540 1285);
PAINT MONO (-5540 1285);
DISPLAY INVISIBLE (-5540 1285);
FORCEPROP 1 LASTPIN (-5550 1275) BN 4
J 0
(-5602 1283);
DISPLAY 0.617021 (-5602 1283);
PAINT GREEN (-5602 1283);
FORCEPROP 2 LAST CDS_LIB mstr_standard
J 0
(-5600 1275);
PAINT MONO (-5600 1275);
DISPLAY INVISIBLE (-5600 1275);
FORCEPROP 1 LAST BODY_TYPE PLUMBING
J 0
(-5600 1225);
DISPLAY 1.595745 (-5600 1225);
PAINT GREEN (-5600 1225);
DISPLAY INVISIBLE (-5600 1225);
FORCEPROP 1 LAST HDL_TAP TRUE
J 0
(-5275 1150);
DISPLAY 1.595745 (-5275 1150);
PAINT GREEN (-5275 1150);
DISPLAY INVISIBLE (-5275 1150);
FORCEPROP 1 LAST PATH I16
J 0
(-5602 1275);
DISPLAY 0.872340 (-5602 1275);
PAINT GREEN (-5602 1275);
DISPLAY INVISIBLE (-5602 1275);
FORCEADD TAP..6
R 2
(-2875 4175);
FORCEPROP 3 LASTPIN (-2925 4175) SIG_NAME M_H_DQS_DP<7>
J 0
(-2915 4185);
DISPLAY 0.659574 (-2915 4185);
PAINT MONO (-2915 4185);
DISPLAY INVISIBLE (-2915 4185);
FORCEPROP 1 LASTPIN (-2925 4175) BN 7
J 2
(-2873 4183);
DISPLAY 0.617021 (-2873 4183);
PAINT GREEN (-2873 4183);
FORCEPROP 2 LAST CDS_LIB mstr_standard
J 0
(-2875 4175);
PAINT MONO (-2875 4175);
DISPLAY INVISIBLE (-2875 4175);
FORCEPROP 1 LAST BODY_TYPE PLUMBING
J 2
(-2875 4125);
DISPLAY 1.595745 (-2875 4125);
PAINT GREEN (-2875 4125);
DISPLAY INVISIBLE (-2875 4125);
FORCEPROP 1 LAST HDL_TAP TRUE
J 2
(-3200 4050);
DISPLAY 1.595745 (-3200 4050);
PAINT GREEN (-3200 4050);
DISPLAY INVISIBLE (-3200 4050);
FORCEPROP 1 LAST PATH I160
J 2
(-2873 4175);
DISPLAY 0.872340 (-2873 4175);
PAINT GREEN (-2873 4175);
DISPLAY INVISIBLE (-2873 4175);
FORCEADD TAP..6
R 2
(-2875 4225);
FORCEPROP 3 LASTPIN (-2925 4225) SIG_NAME M_H_DQS_DP<8>
J 0
(-2915 4235);
DISPLAY 0.659574 (-2915 4235);
PAINT MONO (-2915 4235);
DISPLAY INVISIBLE (-2915 4235);
FORCEPROP 1 LASTPIN (-2925 4225) BN 8
J 2
(-2873 4233);
DISPLAY 0.617021 (-2873 4233);
PAINT GREEN (-2873 4233);
FORCEPROP 2 LAST CDS_LIB mstr_standard
J 0
(-2875 4225);
PAINT MONO (-2875 4225);
DISPLAY INVISIBLE (-2875 4225);
FORCEPROP 1 LAST BODY_TYPE PLUMBING
J 2
(-2875 4175);
DISPLAY 1.595745 (-2875 4175);
PAINT GREEN (-2875 4175);
DISPLAY INVISIBLE (-2875 4175);
FORCEPROP 1 LAST HDL_TAP TRUE
J 2
(-3200 4100);
DISPLAY 1.595745 (-3200 4100);
PAINT GREEN (-3200 4100);
DISPLAY INVISIBLE (-3200 4100);
FORCEPROP 1 LAST PATH I161
J 2
(-2873 4225);
DISPLAY 0.872340 (-2873 4225);
PAINT GREEN (-2873 4225);
DISPLAY INVISIBLE (-2873 4225);
FORCEADD TAP..6
R 2
(-2875 4275);
FORCEPROP 3 LASTPIN (-2925 4275) SIG_NAME M_H_DQS_DP<9>
J 0
(-2915 4285);
DISPLAY 0.659574 (-2915 4285);
PAINT MONO (-2915 4285);
DISPLAY INVISIBLE (-2915 4285);
FORCEPROP 1 LASTPIN (-2925 4275) BN 9
J 2
(-2873 4283);
DISPLAY 0.617021 (-2873 4283);
PAINT GREEN (-2873 4283);
FORCEPROP 2 LAST CDS_LIB mstr_standard
J 0
(-2875 4275);
PAINT MONO (-2875 4275);
DISPLAY INVISIBLE (-2875 4275);
FORCEPROP 1 LAST BODY_TYPE PLUMBING
J 2
(-2875 4225);
DISPLAY 1.595745 (-2875 4225);
PAINT GREEN (-2875 4225);
DISPLAY INVISIBLE (-2875 4225);
FORCEPROP 1 LAST HDL_TAP TRUE
J 2
(-3200 4150);
DISPLAY 1.595745 (-3200 4150);
PAINT GREEN (-3200 4150);
DISPLAY INVISIBLE (-3200 4150);
FORCEPROP 1 LAST PATH I162
J 2
(-2873 4275);
DISPLAY 0.872340 (-2873 4275);
PAINT GREEN (-2873 4275);
DISPLAY INVISIBLE (-2873 4275);
FORCEADD TAP..6
R 2
(-2875 4325);
FORCEPROP 3 LASTPIN (-2925 4325) SIG_NAME M_H_DQS_DP<10>
J 0
(-2915 4335);
DISPLAY 0.659574 (-2915 4335);
PAINT MONO (-2915 4335);
DISPLAY INVISIBLE (-2915 4335);
FORCEPROP 1 LASTPIN (-2925 4325) BN 10
J 2
(-2873 4333);
DISPLAY 0.617021 (-2873 4333);
PAINT GREEN (-2873 4333);
FORCEPROP 2 LAST CDS_LIB mstr_standard
J 0
(-2875 4325);
PAINT MONO (-2875 4325);
DISPLAY INVISIBLE (-2875 4325);
FORCEPROP 1 LAST BODY_TYPE PLUMBING
J 2
(-2875 4275);
DISPLAY 1.595745 (-2875 4275);
PAINT GREEN (-2875 4275);
DISPLAY INVISIBLE (-2875 4275);
FORCEPROP 1 LAST HDL_TAP TRUE
J 2
(-3200 4200);
DISPLAY 1.595745 (-3200 4200);
PAINT GREEN (-3200 4200);
DISPLAY INVISIBLE (-3200 4200);
FORCEPROP 1 LAST PATH I163
J 2
(-2873 4325);
DISPLAY 0.872340 (-2873 4325);
PAINT GREEN (-2873 4325);
DISPLAY INVISIBLE (-2873 4325);
FORCEADD TAP..6
R 2
(-2875 4375);
FORCEPROP 3 LASTPIN (-2925 4375) SIG_NAME M_H_DQS_DP<11>
J 0
(-2915 4385);
DISPLAY 0.659574 (-2915 4385);
PAINT MONO (-2915 4385);
DISPLAY INVISIBLE (-2915 4385);
FORCEPROP 1 LASTPIN (-2925 4375) BN 11
J 2
(-2873 4383);
DISPLAY 0.617021 (-2873 4383);
PAINT GREEN (-2873 4383);
FORCEPROP 2 LAST CDS_LIB mstr_standard
J 0
(-2875 4375);
PAINT MONO (-2875 4375);
DISPLAY INVISIBLE (-2875 4375);
FORCEPROP 1 LAST BODY_TYPE PLUMBING
J 2
(-2875 4325);
DISPLAY 1.595745 (-2875 4325);
PAINT GREEN (-2875 4325);
DISPLAY INVISIBLE (-2875 4325);
FORCEPROP 1 LAST HDL_TAP TRUE
J 2
(-3200 4250);
DISPLAY 1.595745 (-3200 4250);
PAINT GREEN (-3200 4250);
DISPLAY INVISIBLE (-3200 4250);
FORCEPROP 1 LAST PATH I164
J 2
(-2873 4375);
DISPLAY 0.872340 (-2873 4375);
PAINT GREEN (-2873 4375);
DISPLAY INVISIBLE (-2873 4375);
FORCEADD TAP..6
R 2
(-2875 4525);
FORCEPROP 3 LASTPIN (-2925 4525) SIG_NAME M_H_DQS_DP<14>
J 0
(-2915 4535);
DISPLAY 0.659574 (-2915 4535);
PAINT MONO (-2915 4535);
DISPLAY INVISIBLE (-2915 4535);
FORCEPROP 1 LASTPIN (-2925 4525) BN 14
J 2
(-2873 4533);
DISPLAY 0.617021 (-2873 4533);
PAINT GREEN (-2873 4533);
FORCEPROP 2 LAST CDS_LIB mstr_standard
J 0
(-2875 4525);
PAINT MONO (-2875 4525);
DISPLAY INVISIBLE (-2875 4525);
FORCEPROP 1 LAST BODY_TYPE PLUMBING
J 2
(-2875 4475);
DISPLAY 1.595745 (-2875 4475);
PAINT GREEN (-2875 4475);
DISPLAY INVISIBLE (-2875 4475);
FORCEPROP 1 LAST HDL_TAP TRUE
J 2
(-3200 4400);
DISPLAY 1.595745 (-3200 4400);
PAINT GREEN (-3200 4400);
DISPLAY INVISIBLE (-3200 4400);
FORCEPROP 1 LAST PATH I165
J 2
(-2873 4525);
DISPLAY 0.872340 (-2873 4525);
PAINT GREEN (-2873 4525);
DISPLAY INVISIBLE (-2873 4525);
FORCEADD TAP..6
R 2
(-2875 4475);
FORCEPROP 3 LASTPIN (-2925 4475) SIG_NAME M_H_DQS_DP<13>
J 0
(-2915 4485);
DISPLAY 0.659574 (-2915 4485);
PAINT MONO (-2915 4485);
DISPLAY INVISIBLE (-2915 4485);
FORCEPROP 1 LASTPIN (-2925 4475) BN 13
J 2
(-2873 4483);
DISPLAY 0.617021 (-2873 4483);
PAINT GREEN (-2873 4483);
FORCEPROP 2 LAST CDS_LIB mstr_standard
J 0
(-2875 4475);
PAINT MONO (-2875 4475);
DISPLAY INVISIBLE (-2875 4475);
FORCEPROP 1 LAST BODY_TYPE PLUMBING
J 2
(-2875 4425);
DISPLAY 1.595745 (-2875 4425);
PAINT GREEN (-2875 4425);
DISPLAY INVISIBLE (-2875 4425);
FORCEPROP 1 LAST HDL_TAP TRUE
J 2
(-3200 4350);
DISPLAY 1.595745 (-3200 4350);
PAINT GREEN (-3200 4350);
DISPLAY INVISIBLE (-3200 4350);
FORCEPROP 1 LAST PATH I166
J 2
(-2873 4475);
DISPLAY 0.872340 (-2873 4475);
PAINT GREEN (-2873 4475);
DISPLAY INVISIBLE (-2873 4475);
FORCEADD TAP..6
R 2
(-2875 4425);
FORCEPROP 3 LASTPIN (-2925 4425) SIG_NAME M_H_DQS_DP<12>
J 0
(-2915 4435);
DISPLAY 0.659574 (-2915 4435);
PAINT MONO (-2915 4435);
DISPLAY INVISIBLE (-2915 4435);
FORCEPROP 1 LASTPIN (-2925 4425) BN 12
J 2
(-2873 4433);
DISPLAY 0.617021 (-2873 4433);
PAINT GREEN (-2873 4433);
FORCEPROP 2 LAST CDS_LIB mstr_standard
J 0
(-2875 4425);
PAINT MONO (-2875 4425);
DISPLAY INVISIBLE (-2875 4425);
FORCEPROP 1 LAST BODY_TYPE PLUMBING
J 2
(-2875 4375);
DISPLAY 1.595745 (-2875 4375);
PAINT GREEN (-2875 4375);
DISPLAY INVISIBLE (-2875 4375);
FORCEPROP 1 LAST HDL_TAP TRUE
J 2
(-3200 4300);
DISPLAY 1.595745 (-3200 4300);
PAINT GREEN (-3200 4300);
DISPLAY INVISIBLE (-3200 4300);
FORCEPROP 1 LAST PATH I167
J 2
(-2873 4425);
DISPLAY 0.872340 (-2873 4425);
PAINT GREEN (-2873 4425);
DISPLAY INVISIBLE (-2873 4425);
FORCEADD TAP..6
R 2
(-2875 4575);
FORCEPROP 3 LASTPIN (-2925 4575) SIG_NAME M_H_DQS_DP<15>
J 0
(-2915 4585);
DISPLAY 0.659574 (-2915 4585);
PAINT MONO (-2915 4585);
DISPLAY INVISIBLE (-2915 4585);
FORCEPROP 1 LASTPIN (-2925 4575) BN 15
J 2
(-2873 4583);
DISPLAY 0.617021 (-2873 4583);
PAINT GREEN (-2873 4583);
FORCEPROP 2 LAST CDS_LIB mstr_standard
J 0
(-2875 4575);
PAINT MONO (-2875 4575);
DISPLAY INVISIBLE (-2875 4575);
FORCEPROP 1 LAST BODY_TYPE PLUMBING
J 2
(-2875 4525);
DISPLAY 1.595745 (-2875 4525);
PAINT GREEN (-2875 4525);
DISPLAY INVISIBLE (-2875 4525);
FORCEPROP 1 LAST HDL_TAP TRUE
J 2
(-3200 4450);
DISPLAY 1.595745 (-3200 4450);
PAINT GREEN (-3200 4450);
DISPLAY INVISIBLE (-3200 4450);
FORCEPROP 1 LAST PATH I168
J 2
(-2873 4575);
DISPLAY 0.872340 (-2873 4575);
PAINT GREEN (-2873 4575);
DISPLAY INVISIBLE (-2873 4575);
FORCEADD TAP..6
R 2
(-2875 4625);
FORCEPROP 3 LASTPIN (-2925 4625) SIG_NAME M_H_DQS_DP<16>
J 0
(-2915 4635);
DISPLAY 0.659574 (-2915 4635);
PAINT MONO (-2915 4635);
DISPLAY INVISIBLE (-2915 4635);
FORCEPROP 1 LASTPIN (-2925 4625) BN 16
J 2
(-2873 4633);
DISPLAY 0.617021 (-2873 4633);
PAINT GREEN (-2873 4633);
FORCEPROP 2 LAST CDS_LIB mstr_standard
J 0
(-2875 4625);
PAINT MONO (-2875 4625);
DISPLAY INVISIBLE (-2875 4625);
FORCEPROP 1 LAST BODY_TYPE PLUMBING
J 2
(-2875 4575);
DISPLAY 1.595745 (-2875 4575);
PAINT GREEN (-2875 4575);
DISPLAY INVISIBLE (-2875 4575);
FORCEPROP 1 LAST HDL_TAP TRUE
J 2
(-3200 4500);
DISPLAY 1.595745 (-3200 4500);
PAINT GREEN (-3200 4500);
DISPLAY INVISIBLE (-3200 4500);
FORCEPROP 1 LAST PATH I169
J 2
(-2873 4625);
DISPLAY 0.872340 (-2873 4625);
PAINT GREEN (-2873 4625);
DISPLAY INVISIBLE (-2873 4625);
FORCEADD TAP..6
(-5600 1225);
FORCEPROP 3 LASTPIN (-5550 1225) SIG_NAME M_H_ECC<3>
J 0
(-5540 1235);
DISPLAY 0.659574 (-5540 1235);
PAINT MONO (-5540 1235);
DISPLAY INVISIBLE (-5540 1235);
FORCEPROP 1 LASTPIN (-5550 1225) BN 3
J 0
(-5602 1233);
DISPLAY 0.617021 (-5602 1233);
PAINT GREEN (-5602 1233);
FORCEPROP 2 LAST CDS_LIB mstr_standard
J 0
(-5600 1225);
PAINT MONO (-5600 1225);
DISPLAY INVISIBLE (-5600 1225);
FORCEPROP 1 LAST BODY_TYPE PLUMBING
J 0
(-5600 1175);
DISPLAY 1.595745 (-5600 1175);
PAINT GREEN (-5600 1175);
DISPLAY INVISIBLE (-5600 1175);
FORCEPROP 1 LAST HDL_TAP TRUE
J 0
(-5275 1100);
DISPLAY 1.595745 (-5275 1100);
PAINT GREEN (-5275 1100);
DISPLAY INVISIBLE (-5275 1100);
FORCEPROP 1 LAST PATH I17
J 0
(-5602 1225);
DISPLAY 0.872340 (-5602 1225);
PAINT GREEN (-5602 1225);
DISPLAY INVISIBLE (-5602 1225);
FORCEADD TAP..6
R 2
(-2875 4675);
FORCEPROP 3 LASTPIN (-2925 4675) SIG_NAME M_H_DQS_DP<17>
J 0
(-2915 4685);
DISPLAY 0.659574 (-2915 4685);
PAINT MONO (-2915 4685);
DISPLAY INVISIBLE (-2915 4685);
FORCEPROP 1 LASTPIN (-2925 4675) BN 17
J 2
(-2873 4683);
DISPLAY 0.617021 (-2873 4683);
PAINT GREEN (-2873 4683);
FORCEPROP 2 LAST CDS_LIB mstr_standard
J 2
(-2875 4675);
PAINT MONO (-2875 4675);
DISPLAY INVISIBLE (-2875 4675);
FORCEPROP 1 LAST BODY_TYPE PLUMBING
J 2
(-2875 4625);
DISPLAY 1.595745 (-2875 4625);
PAINT GREEN (-2875 4625);
DISPLAY INVISIBLE (-2875 4625);
FORCEPROP 1 LAST HDL_TAP TRUE
J 2
(-3200 4550);
DISPLAY 1.595745 (-3200 4550);
PAINT GREEN (-3200 4550);
DISPLAY INVISIBLE (-3200 4550);
FORCEPROP 1 LAST PATH I170
J 2
(-2873 4675);
DISPLAY 0.872340 (-2873 4675);
PAINT GREEN (-2873 4675);
DISPLAY INVISIBLE (-2873 4675);
FORCEADD OFFPAGE..3
(-2025 4750);
FORCEPROP 2 LAST $XR1 80 
J 0
(-1721 4750);
DISPLAY 0.638298 (-1721 4750);
PAINT MONO (-1721 4750);
FORCEPROP 2 LAST $XR0 79 
J 0
(-1811 4750);
DISPLAY 0.638298 (-1811 4750);
PAINT MONO (-1811 4750);
FORCEPROP 2 LAST CDS_LIB mstr_standard
J 0
(-2025 4750);
PAINT MONO (-2025 4750);
DISPLAY INVISIBLE (-2025 4750);
FORCEPROP 1 LAST OFFPAGE TRUE
J 0
(-1700 4625);
DISPLAY 1.170213 (-1700 4625);
PAINT GREEN (-1700 4625);
DISPLAY INVISIBLE (-1700 4625);
FORCEPROP 1 LAST COMMENT_BODY TRUE
J 0
(-2075 4650);
DISPLAY 1.170213 (-2075 4650);
PAINT GREEN (-2075 4650);
DISPLAY INVISIBLE (-2075 4650);
FORCEPROP 2 LAST PATH I171
J 0
(-1825 4825);
DISPLAY 1.021277 (-1825 4825);
PAINT ORANGE (-1825 4825);
DISPLAY INVISIBLE (-1825 4825);
FORCEADD SKX_EXT_B..4
(-4200 2575);
FORCEPROP 1 LAST LOCATION U2D1
J 0
(-5000 4925);
DISPLAY 0.617021 (-5000 4925);
PAINT AQUA (-5000 4925);
FORCEPROP 1 LAST PART_NUMBER TBD
J 0
(-5000 325);
DISPLAY 0.617021 (-5000 325);
PAINT BLUE (-5000 325);
FORCEPROP 1 LAST MATERIAL IC
J 0
(-5000 4875);
DISPLAY 0.617021 (-5000 4875);
PAINT SKYBLUE (-5000 4875);
FORCEPROP 2 LASTPIN (-3350 525) $PN K53
J 0
(-3340 535);
DISPLAY 0.617021 (-3340 535);
PAINT ORANGE (-3340 535);
FORCEPROP 2 LASTPIN (-3350 1575) $PN T47
J 0
(-3340 1585);
DISPLAY 0.617021 (-3340 1585);
PAINT ORANGE (-3340 1585);
FORCEPROP 2 LASTPIN (-3350 1525) $PN M49
J 0
(-3340 1535);
DISPLAY 0.617021 (-3340 1535);
PAINT ORANGE (-3340 1535);
FORCEPROP 2 LASTPIN (-3350 1475) $PN R48
J 0
(-3340 1485);
DISPLAY 0.617021 (-3340 1485);
PAINT ORANGE (-3340 1485);
FORCEPROP 2 LASTPIN (-3350 1425) $PN N50
J 0
(-3340 1435);
DISPLAY 0.617021 (-3340 1435);
PAINT ORANGE (-3340 1435);
FORCEPROP 2 LASTPIN (-3350 2775) $PN N48
J 0
(-3340 2785);
DISPLAY 0.617021 (-3340 2785);
PAINT ORANGE (-3340 2785);
FORCEPROP 2 LASTPIN (-3350 2725) $PN R52
J 0
(-3340 2735);
DISPLAY 0.617021 (-3340 2735);
PAINT ORANGE (-3340 2735);
FORCEPROP 2 LASTPIN (-3350 2675) $PN N52
J 0
(-3340 2685);
DISPLAY 0.617021 (-3340 2685);
PAINT ORANGE (-3340 2685);
FORCEPROP 2 LASTPIN (-3350 2625) $PN T51
J 0
(-3340 2635);
DISPLAY 0.617021 (-3340 2635);
PAINT ORANGE (-3340 2635);
FORCEPROP 2 LASTPIN (-3350 2575) $PN M51
J 0
(-3340 2585);
DISPLAY 0.617021 (-3340 2585);
PAINT ORANGE (-3340 2585);
FORCEPROP 2 LASTPIN (-3350 2525) $PN T61
J 0
(-3340 2535);
DISPLAY 0.617021 (-3340 2535);
PAINT ORANGE (-3340 2535);
FORCEPROP 2 LASTPIN (-3350 2475) $PN R60
J 0
(-3340 2485);
DISPLAY 0.617021 (-3340 2485);
PAINT ORANGE (-3340 2485);
FORCEPROP 2 LASTPIN (-3350 2425) $PN M55
J 0
(-3340 2435);
DISPLAY 0.617021 (-3340 2435);
PAINT ORANGE (-3340 2435);
FORCEPROP 2 LASTPIN (-3350 2375) $PN K59
J 0
(-3340 2385);
DISPLAY 0.617021 (-3340 2385);
PAINT ORANGE (-3340 2385);
FORCEPROP 2 LASTPIN (-3350 2325) $PN W60
J 0
(-3340 2335);
DISPLAY 0.617021 (-3340 2335);
PAINT ORANGE (-3340 2335);
FORCEPROP 2 LASTPIN (-3350 2275) $PN V61
J 0
(-3340 2285);
DISPLAY 0.617021 (-3340 2285);
PAINT ORANGE (-3340 2285);
FORCEPROP 2 LASTPIN (-3350 2225) $PN T59
J 0
(-3340 2235);
DISPLAY 0.617021 (-3340 2235);
PAINT ORANGE (-3340 2235);
FORCEPROP 2 LASTPIN (-3350 2175) $PN R58
J 0
(-3340 2185);
DISPLAY 0.617021 (-3340 2185);
PAINT ORANGE (-3340 2185);
FORCEPROP 2 LASTPIN (-3350 2125) $PN M59
J 0
(-3340 2135);
DISPLAY 0.617021 (-3340 2135);
PAINT ORANGE (-3340 2135);
FORCEPROP 2 LASTPIN (-3350 2075) $PN N58
J 0
(-3340 2085);
DISPLAY 0.617021 (-3340 2085);
PAINT ORANGE (-3340 2085);
FORCEPROP 2 LASTPIN (-3350 2025) $PN K57
J 0
(-3340 2035);
DISPLAY 0.617021 (-3340 2035);
PAINT ORANGE (-3340 2035);
FORCEPROP 2 LASTPIN (-3350 1975) $PN J58
J 0
(-3340 1985);
DISPLAY 0.617021 (-3340 1985);
PAINT ORANGE (-3340 1985);
FORCEPROP 2 LASTPIN (-3350 1925) $PN J52
J 0
(-3340 1935);
DISPLAY 0.617021 (-3340 1935);
PAINT ORANGE (-3340 1935);
FORCEPROP 2 LASTPIN (-5050 1425) $PN M67
J 2
(-5060 1435);
DISPLAY 0.617021 (-5060 1435);
PAINT ORANGE (-5060 1435);
FORCEPROP 2 LASTPIN (-5050 1375) $PN H67
J 2
(-5060 1385);
DISPLAY 0.617021 (-5060 1385);
PAINT ORANGE (-5060 1385);
FORCEPROP 2 LASTPIN (-5050 1325) $PN M69
J 2
(-5060 1335);
DISPLAY 0.617021 (-5060 1335);
PAINT ORANGE (-5060 1335);
FORCEPROP 2 LASTPIN (-5050 1275) $PN L70
J 2
(-5060 1285);
DISPLAY 0.617021 (-5060 1285);
PAINT ORANGE (-5060 1285);
FORCEPROP 2 LASTPIN (-5050 1225) $PN L66
J 2
(-5060 1235);
DISPLAY 0.617021 (-5060 1235);
PAINT ORANGE (-5060 1235);
FORCEPROP 2 LASTPIN (-5050 1175) $PN J66
J 2
(-5060 1185);
DISPLAY 0.617021 (-5060 1185);
PAINT ORANGE (-5060 1185);
FORCEPROP 2 LASTPIN (-5050 1125) $PN H69
J 2
(-5060 1135);
DISPLAY 0.617021 (-5060 1135);
PAINT ORANGE (-5060 1135);
FORCEPROP 2 LASTPIN (-5050 1075) $PN J70
J 2
(-5060 1085);
DISPLAY 0.617021 (-5060 1085);
PAINT ORANGE (-5060 1085);
FORCEPROP 2 LASTPIN (-3350 4675) $PN J68
J 0
(-3340 4685);
DISPLAY 0.617021 (-3340 4685);
PAINT ORANGE (-3340 4685);
FORCEPROP 2 LASTPIN (-3350 4625) $PN V27
J 0
(-3340 4635);
DISPLAY 0.617021 (-3340 4635);
PAINT ORANGE (-3340 4635);
FORCEPROP 2 LASTPIN (-3350 4575) $PN C28
J 0
(-3340 4585);
DISPLAY 0.617021 (-3340 4585);
PAINT ORANGE (-3340 4585);
FORCEPROP 2 LASTPIN (-3350 4525) $PN C34
J 0
(-3340 4535);
DISPLAY 0.617021 (-3340 4535);
PAINT ORANGE (-3340 4535);
FORCEPROP 2 LASTPIN (-3350 4475) $PN L42
J 0
(-3340 4485);
DISPLAY 0.617021 (-3340 4485);
PAINT ORANGE (-3340 4485);
FORCEPROP 2 LASTPIN (-3350 4425) $PN D73
J 0
(-3340 4435);
DISPLAY 0.617021 (-3340 4435);
PAINT ORANGE (-3340 4435);
FORCEPROP 2 LASTPIN (-3350 4375) $PN F79
J 0
(-3340 4385);
DISPLAY 0.617021 (-3340 4385);
PAINT ORANGE (-3340 4385);
FORCEPROP 2 LASTPIN (-3350 4325) $PN AF81
J 0
(-3340 4335);
DISPLAY 0.617021 (-3340 4335);
PAINT ORANGE (-3340 4335);
FORCEPROP 2 LASTPIN (-3350 4275) $PN AT81
J 0
(-3340 4285);
DISPLAY 0.617021 (-3340 4285);
PAINT ORANGE (-3340 4285);
FORCEPROP 2 LASTPIN (-3350 4225) $PN L68
J 0
(-3340 4235);
DISPLAY 0.617021 (-3340 4235);
PAINT ORANGE (-3340 4235);
FORCEPROP 2 LASTPIN (-3350 4175) $PN Y27
J 0
(-3340 4185);
DISPLAY 0.617021 (-3340 4185);
PAINT ORANGE (-3340 4185);
FORCEPROP 2 LASTPIN (-3350 4125) $PN E28
J 0
(-3340 4135);
DISPLAY 0.617021 (-3340 4135);
PAINT ORANGE (-3340 4135);
FORCEPROP 2 LASTPIN (-3350 4075) $PN E34
J 0
(-3340 4085);
DISPLAY 0.617021 (-3340 4085);
PAINT ORANGE (-3340 4085);
FORCEPROP 2 LASTPIN (-3350 4025) $PN R42
J 0
(-3340 4035);
DISPLAY 0.617021 (-3340 4035);
PAINT ORANGE (-3340 4035);
FORCEPROP 2 LASTPIN (-3350 3975) $PN F73
J 0
(-3340 3985);
DISPLAY 0.617021 (-3340 3985);
PAINT ORANGE (-3340 3985);
FORCEPROP 2 LASTPIN (-3350 3925) $PN H79
J 0
(-3340 3935);
DISPLAY 0.617021 (-3340 3935);
PAINT ORANGE (-3340 3935);
FORCEPROP 2 LASTPIN (-3350 3875) $PN AE80
J 0
(-3340 3885);
DISPLAY 0.617021 (-3340 3885);
PAINT ORANGE (-3340 3885);
FORCEPROP 2 LASTPIN (-3350 3825) $PN AR80
J 0
(-3340 3835);
DISPLAY 0.617021 (-3340 3835);
PAINT ORANGE (-3340 3835);
FORCEPROP 2 LASTPIN (-3350 3725) $PN G68
J 0
(-3340 3735);
DISPLAY 0.617021 (-3340 3735);
PAINT ORANGE (-3340 3735);
FORCEPROP 2 LASTPIN (-3350 3675) $PN T27
J 0
(-3340 3685);
DISPLAY 0.617021 (-3340 3685);
PAINT ORANGE (-3340 3685);
FORCEPROP 2 LASTPIN (-3350 3625) $PN A28
J 0
(-3340 3635);
DISPLAY 0.617021 (-3340 3635);
PAINT ORANGE (-3340 3635);
FORCEPROP 2 LASTPIN (-3350 3575) $PN A34
J 0
(-3340 3585);
DISPLAY 0.617021 (-3340 3585);
PAINT ORANGE (-3340 3585);
FORCEPROP 2 LASTPIN (-3350 3525) $PN J42
J 0
(-3340 3535);
DISPLAY 0.617021 (-3340 3535);
PAINT ORANGE (-3340 3535);
FORCEPROP 2 LASTPIN (-3350 3475) $PN B73
J 0
(-3340 3485);
DISPLAY 0.617021 (-3340 3485);
PAINT ORANGE (-3340 3485);
FORCEPROP 2 LASTPIN (-3350 3425) $PN D79
J 0
(-3340 3435);
DISPLAY 0.617021 (-3340 3435);
PAINT ORANGE (-3340 3435);
FORCEPROP 2 LASTPIN (-3350 3375) $PN AG82
J 0
(-3340 3385);
DISPLAY 0.617021 (-3340 3385);
PAINT ORANGE (-3340 3385);
FORCEPROP 2 LASTPIN (-3350 3325) $PN AU82
J 0
(-3340 3335);
DISPLAY 0.617021 (-3340 3335);
PAINT ORANGE (-3340 3335);
FORCEPROP 2 LASTPIN (-3350 3275) $PN N68
J 0
(-3340 3285);
DISPLAY 0.617021 (-3340 3285);
PAINT ORANGE (-3340 3285);
FORCEPROP 2 LASTPIN (-3350 3225) $PN AB27
J 0
(-3340 3235);
DISPLAY 0.617021 (-3340 3235);
PAINT ORANGE (-3340 3235);
FORCEPROP 2 LASTPIN (-3350 3175) $PN G28
J 0
(-3340 3185);
DISPLAY 0.617021 (-3340 3185);
PAINT ORANGE (-3340 3185);
FORCEPROP 2 LASTPIN (-3350 3125) $PN G34
J 0
(-3340 3135);
DISPLAY 0.617021 (-3340 3135);
PAINT ORANGE (-3340 3135);
FORCEPROP 2 LASTPIN (-3350 3075) $PN N42
J 0
(-3340 3085);
DISPLAY 0.617021 (-3340 3085);
PAINT ORANGE (-3340 3085);
FORCEPROP 2 LASTPIN (-3350 3025) $PN H73
J 0
(-3340 3035);
DISPLAY 0.617021 (-3340 3035);
PAINT ORANGE (-3340 3035);
FORCEPROP 2 LASTPIN (-3350 2975) $PN K79
J 0
(-3340 2985);
DISPLAY 0.617021 (-3340 2985);
PAINT ORANGE (-3340 2985);
FORCEPROP 2 LASTPIN (-3350 2925) $PN AD79
J 0
(-3340 2935);
DISPLAY 0.617021 (-3340 2935);
PAINT ORANGE (-3340 2935);
FORCEPROP 2 LASTPIN (-3350 2875) $PN AP79
J 0
(-3340 2885);
DISPLAY 0.617021 (-3340 2885);
PAINT ORANGE (-3340 2885);
FORCEPROP 2 LASTPIN (-5050 4675) $PN AA26
J 2
(-5060 4685);
DISPLAY 0.617021 (-5060 4685);
PAINT ORANGE (-5060 4685);
FORCEPROP 2 LASTPIN (-5050 4625) $PN U26
J 2
(-5060 4635);
DISPLAY 0.617021 (-5060 4635);
PAINT ORANGE (-5060 4635);
FORCEPROP 2 LASTPIN (-5050 4575) $PN Y29
J 2
(-5060 4585);
DISPLAY 0.617021 (-5060 4585);
PAINT ORANGE (-5060 4585);
FORCEPROP 2 LASTPIN (-5050 4525) $PN V29
J 2
(-5060 4535);
DISPLAY 0.617021 (-5060 4535);
PAINT ORANGE (-5060 4535);
FORCEPROP 2 LASTPIN (-5050 4475) $PN Y25
J 2
(-5060 4485);
DISPLAY 0.617021 (-5060 4485);
PAINT ORANGE (-5060 4485);
FORCEPROP 2 LASTPIN (-5050 4425) $PN V25
J 2
(-5060 4435);
DISPLAY 0.617021 (-5060 4435);
PAINT ORANGE (-5060 4435);
FORCEPROP 2 LASTPIN (-5050 4375) $PN AA28
J 2
(-5060 4385);
DISPLAY 0.617021 (-5060 4385);
PAINT ORANGE (-5060 4385);
FORCEPROP 2 LASTPIN (-5050 4325) $PN U28
J 2
(-5060 4335);
DISPLAY 0.617021 (-5060 4335);
PAINT ORANGE (-5060 4335);
FORCEPROP 2 LASTPIN (-5050 4275) $PN F27
J 2
(-5060 4285);
DISPLAY 0.617021 (-5060 4285);
PAINT ORANGE (-5060 4285);
FORCEPROP 2 LASTPIN (-5050 4225) $PN B27
J 2
(-5060 4235);
DISPLAY 0.617021 (-5060 4235);
PAINT ORANGE (-5060 4235);
FORCEPROP 2 LASTPIN (-5050 4175) $PN F29
J 2
(-5060 4185);
DISPLAY 0.617021 (-5060 4185);
PAINT ORANGE (-5060 4185);
FORCEPROP 2 LASTPIN (-5050 4125) $PN E30
J 2
(-5060 4135);
DISPLAY 0.617021 (-5060 4135);
PAINT ORANGE (-5060 4135);
FORCEPROP 2 LASTPIN (-5050 4075) $PN E26
J 2
(-5060 4085);
DISPLAY 0.617021 (-5060 4085);
PAINT ORANGE (-5060 4085);
FORCEPROP 2 LASTPIN (-5050 4025) $PN C26
J 2
(-5060 4035);
DISPLAY 0.617021 (-5060 4035);
PAINT ORANGE (-5060 4035);
FORCEPROP 2 LASTPIN (-5050 3975) $PN B29
J 2
(-5060 3985);
DISPLAY 0.617021 (-5060 3985);
PAINT ORANGE (-5060 3985);
FORCEPROP 2 LASTPIN (-5050 3925) $PN C30
J 2
(-5060 3935);
DISPLAY 0.617021 (-5060 3935);
PAINT ORANGE (-5060 3935);
FORCEPROP 2 LASTPIN (-5050 3875) $PN F33
J 2
(-5060 3885);
DISPLAY 0.617021 (-5060 3885);
PAINT ORANGE (-5060 3885);
FORCEPROP 2 LASTPIN (-5050 3825) $PN B33
J 2
(-5060 3835);
DISPLAY 0.617021 (-5060 3835);
PAINT ORANGE (-5060 3835);
FORCEPROP 2 LASTPIN (-5050 3775) $PN F35
J 2
(-5060 3785);
DISPLAY 0.617021 (-5060 3785);
PAINT ORANGE (-5060 3785);
FORCEPROP 2 LASTPIN (-5050 3725) $PN E36
J 2
(-5060 3735);
DISPLAY 0.617021 (-5060 3735);
PAINT ORANGE (-5060 3735);
FORCEPROP 2 LASTPIN (-5050 3675) $PN E32
J 2
(-5060 3685);
DISPLAY 0.617021 (-5060 3685);
PAINT ORANGE (-5060 3685);
FORCEPROP 2 LASTPIN (-5050 3625) $PN C32
J 2
(-5060 3635);
DISPLAY 0.617021 (-5060 3635);
PAINT ORANGE (-5060 3635);
FORCEPROP 2 LASTPIN (-5050 3575) $PN B35
J 2
(-5060 3585);
DISPLAY 0.617021 (-5060 3585);
PAINT ORANGE (-5060 3585);
FORCEPROP 2 LASTPIN (-5050 3525) $PN C36
J 2
(-5060 3535);
DISPLAY 0.617021 (-5060 3535);
PAINT ORANGE (-5060 3535);
FORCEPROP 2 LASTPIN (-5050 3475) $PN P41
J 2
(-5060 3485);
DISPLAY 0.617021 (-5060 3485);
PAINT ORANGE (-5060 3485);
FORCEPROP 2 LASTPIN (-5050 3425) $PN K41
J 2
(-5060 3435);
DISPLAY 0.617021 (-5060 3435);
PAINT ORANGE (-5060 3435);
FORCEPROP 2 LASTPIN (-5050 3375) $PN T43
J 2
(-5060 3385);
DISPLAY 0.617021 (-5060 3385);
PAINT ORANGE (-5060 3385);
FORCEPROP 2 LASTPIN (-5050 3325) $PN P43
J 2
(-5060 3335);
DISPLAY 0.617021 (-5060 3335);
PAINT ORANGE (-5060 3335);
FORCEPROP 2 LASTPIN (-5050 3275) $PN N40
J 2
(-5060 3285);
DISPLAY 0.617021 (-5060 3285);
PAINT ORANGE (-5060 3285);
FORCEPROP 2 LASTPIN (-5050 3225) $PN L40
J 2
(-5060 3235);
DISPLAY 0.617021 (-5060 3235);
PAINT ORANGE (-5060 3235);
FORCEPROP 2 LASTPIN (-5050 3175) $PN H43
J 2
(-5060 3185);
DISPLAY 0.617021 (-5060 3185);
PAINT ORANGE (-5060 3185);
FORCEPROP 2 LASTPIN (-5050 3125) $PN K43
J 2
(-5060 3135);
DISPLAY 0.617021 (-5060 3135);
PAINT ORANGE (-5060 3135);
FORCEPROP 2 LASTPIN (-5050 3075) $PN G72
J 2
(-5060 3085);
DISPLAY 0.617021 (-5060 3085);
PAINT ORANGE (-5060 3085);
FORCEPROP 2 LASTPIN (-5050 3025) $PN C72
J 2
(-5060 3035);
DISPLAY 0.617021 (-5060 3035);
PAINT ORANGE (-5060 3035);
FORCEPROP 2 LASTPIN (-5050 2975) $PN G74
J 2
(-5060 2985);
DISPLAY 0.617021 (-5060 2985);
PAINT ORANGE (-5060 2985);
FORCEPROP 2 LASTPIN (-5050 2825) $PN D71
J 2
(-5060 2835);
DISPLAY 0.617021 (-5060 2835);
PAINT ORANGE (-5060 2835);
FORCEPROP 2 LASTPIN (-5050 2775) $PN C74
J 2
(-5060 2785);
DISPLAY 0.617021 (-5060 2785);
PAINT ORANGE (-5060 2785);
FORCEPROP 2 LASTPIN (-5050 2725) $PN D75
J 2
(-5060 2735);
DISPLAY 0.617021 (-5060 2735);
PAINT ORANGE (-5060 2735);
FORCEPROP 2 LASTPIN (-5050 2675) $PN J78
J 2
(-5060 2685);
DISPLAY 0.617021 (-5060 2685);
PAINT ORANGE (-5060 2685);
FORCEPROP 2 LASTPIN (-5050 2625) $PN E78
J 2
(-5060 2635);
DISPLAY 0.617021 (-5060 2635);
PAINT ORANGE (-5060 2635);
FORCEPROP 2 LASTPIN (-5050 2575) $PN H81
J 2
(-5060 2585);
DISPLAY 0.617021 (-5060 2585);
PAINT ORANGE (-5060 2585);
FORCEPROP 2 LASTPIN (-5050 2525) $PN F81
J 2
(-5060 2535);
DISPLAY 0.617021 (-5060 2535);
PAINT ORANGE (-5060 2535);
FORCEPROP 2 LASTPIN (-5050 2475) $PN H77
J 2
(-5060 2485);
DISPLAY 0.617021 (-5060 2485);
PAINT ORANGE (-5060 2485);
FORCEPROP 2 LASTPIN (-5050 2425) $PN F77
J 2
(-5060 2435);
DISPLAY 0.617021 (-5060 2435);
PAINT ORANGE (-5060 2435);
FORCEPROP 2 LASTPIN (-5050 2375) $PN J80
J 2
(-5060 2385);
DISPLAY 0.617021 (-5060 2385);
PAINT ORANGE (-5060 2385);
FORCEPROP 2 LASTPIN (-5050 2325) $PN E80
J 2
(-5060 2335);
DISPLAY 0.617021 (-5060 2335);
PAINT ORANGE (-5060 2335);
FORCEPROP 2 LASTPIN (-5050 2275) $PN AC80
J 2
(-5060 2285);
DISPLAY 0.617021 (-5060 2285);
PAINT ORANGE (-5060 2285);
FORCEPROP 2 LASTPIN (-5050 2225) $PN AE82
J 2
(-5060 2235);
DISPLAY 0.617021 (-5060 2235);
PAINT ORANGE (-5060 2235);
FORCEPROP 2 LASTPIN (-5050 2175) $PN AH79
J 2
(-5060 2185);
DISPLAY 0.617021 (-5060 2185);
PAINT ORANGE (-5060 2185);
FORCEPROP 2 LASTPIN (-5050 2125) $PN AJ80
J 2
(-5060 2135);
DISPLAY 0.617021 (-5060 2135);
PAINT ORANGE (-5060 2135);
FORCEPROP 2 LASTPIN (-5050 2075) $PN AB81
J 2
(-5060 2085);
DISPLAY 0.617021 (-5060 2085);
PAINT ORANGE (-5060 2085);
FORCEPROP 2 LASTPIN (-5050 2025) $PN AC82
J 2
(-5060 2035);
DISPLAY 0.617021 (-5060 2035);
PAINT ORANGE (-5060 2035);
FORCEPROP 2 LASTPIN (-5050 1975) $PN AF79
J 2
(-5060 1985);
DISPLAY 0.617021 (-5060 1985);
PAINT ORANGE (-5060 1985);
FORCEPROP 2 LASTPIN (-5050 1925) $PN AH81
J 2
(-5060 1935);
DISPLAY 0.617021 (-5060 1935);
PAINT ORANGE (-5060 1935);
FORCEPROP 2 LASTPIN (-5050 1875) $PN AN80
J 2
(-5060 1885);
DISPLAY 0.617021 (-5060 1885);
PAINT ORANGE (-5060 1885);
FORCEPROP 2 LASTPIN (-5050 1825) $PN AR82
J 2
(-5060 1835);
DISPLAY 0.617021 (-5060 1835);
PAINT ORANGE (-5060 1835);
FORCEPROP 2 LASTPIN (-5050 1775) $PN AV79
J 2
(-5060 1785);
DISPLAY 0.617021 (-5060 1785);
PAINT ORANGE (-5060 1785);
FORCEPROP 2 LASTPIN (-5050 1725) $PN AW80
J 2
(-5060 1735);
DISPLAY 0.617021 (-5060 1735);
PAINT ORANGE (-5060 1735);
FORCEPROP 2 LASTPIN (-5050 1675) $PN AM81
J 2
(-5060 1685);
DISPLAY 0.617021 (-5060 1685);
PAINT ORANGE (-5060 1685);
FORCEPROP 2 LASTPIN (-5050 1625) $PN AN82
J 2
(-5060 1635);
DISPLAY 0.617021 (-5060 1635);
PAINT ORANGE (-5060 1635);
FORCEPROP 2 LASTPIN (-5050 1575) $PN AT79
J 2
(-5060 1585);
DISPLAY 0.617021 (-5060 1585);
PAINT ORANGE (-5060 1585);
FORCEPROP 2 LASTPIN (-5050 1525) $PN AV81
J 2
(-5060 1535);
DISPLAY 0.617021 (-5060 1535);
PAINT ORANGE (-5060 1535);
FORCEPROP 2 LASTPIN (-3350 1325) $PN R46
J 0
(-3340 1335);
DISPLAY 0.617021 (-3340 1335);
PAINT ORANGE (-3340 1335);
FORCEPROP 2 LASTPIN (-3350 1275) $PN M45
J 0
(-3340 1285);
DISPLAY 0.617021 (-3340 1285);
PAINT ORANGE (-3340 1285);
FORCEPROP 2 LASTPIN (-3350 1225) $PN T49
J 0
(-3340 1235);
DISPLAY 0.617021 (-3340 1235);
PAINT ORANGE (-3340 1235);
FORCEPROP 2 LASTPIN (-3350 1175) $PN J50
J 0
(-3340 1185);
DISPLAY 0.617021 (-3340 1185);
PAINT ORANGE (-3340 1185);
FORCEPROP 2 LASTPIN (-3350 1125) $PN V47
J 0
(-3340 1135);
DISPLAY 0.617021 (-3340 1135);
PAINT ORANGE (-3340 1135);
FORCEPROP 2 LASTPIN (-3350 1075) $PN N46
J 0
(-3340 1085);
DISPLAY 0.617021 (-3340 1085);
PAINT ORANGE (-3340 1085);
FORCEPROP 2 LASTPIN (-3350 1025) $PN R50
J 0
(-3340 1035);
DISPLAY 0.617021 (-3340 1035);
PAINT ORANGE (-3340 1035);
FORCEPROP 2 LASTPIN (-3350 975) $PN K51
J 0
(-3340 985);
DISPLAY 0.617021 (-3340 985);
PAINT ORANGE (-3340 985);
FORCEPROP 2 LASTPIN (-5050 975) $PN T57
J 2
(-5060 985);
DISPLAY 0.617021 (-5060 985);
PAINT ORANGE (-5060 985);
FORCEPROP 2 LASTPIN (-5050 925) $PN M57
J 2
(-5060 935);
DISPLAY 0.617021 (-5060 935);
PAINT ORANGE (-5060 935);
FORCEPROP 2 LASTPIN (-5050 875) $PN T55
J 2
(-5060 885);
DISPLAY 0.617021 (-5060 885);
PAINT ORANGE (-5060 885);
FORCEPROP 2 LASTPIN (-5050 825) $PN N54
J 2
(-5060 835);
DISPLAY 0.617021 (-5060 835);
PAINT ORANGE (-5060 835);
FORCEPROP 2 LASTPIN (-5050 775) $PN R56
J 2
(-5060 785);
DISPLAY 0.617021 (-5060 785);
PAINT ORANGE (-5060 785);
FORCEPROP 2 LASTPIN (-5050 725) $PN N56
J 2
(-5060 735);
DISPLAY 0.617021 (-5060 735);
PAINT ORANGE (-5060 735);
FORCEPROP 2 LASTPIN (-5050 675) $PN R54
J 2
(-5060 685);
DISPLAY 0.617021 (-5060 685);
PAINT ORANGE (-5060 685);
FORCEPROP 2 LASTPIN (-5050 625) $PN M53
J 2
(-5060 635);
DISPLAY 0.617021 (-5060 635);
PAINT ORANGE (-5060 635);
FORCEPROP 2 LASTPIN (-3350 1825) $PN L64
J 0
(-3340 1835);
DISPLAY 0.617021 (-3340 1835);
PAINT ORANGE (-3340 1835);
FORCEPROP 2 LASTPIN (-3350 1775) $PN K63
J 0
(-3340 1785);
DISPLAY 0.617021 (-3340 1785);
PAINT ORANGE (-3340 1785);
FORCEPROP 2 LASTPIN (-3350 1725) $PN R64
J 0
(-3340 1735);
DISPLAY 0.617021 (-3340 1735);
PAINT ORANGE (-3340 1735);
FORCEPROP 2 LASTPIN (-3350 1675) $PN N62
J 0
(-3340 1685);
DISPLAY 0.617021 (-3340 1685);
PAINT ORANGE (-3340 1685);
FORCEPROP 2 LASTPIN (-5050 525) $PN M47
J 2
(-5060 535);
DISPLAY 0.617021 (-5060 535);
PAINT ORANGE (-5060 535);
FORCEPROP 2 LASTPIN (-3350 875) $PN N60
J 0
(-3340 885);
DISPLAY 0.617021 (-3340 885);
PAINT ORANGE (-3340 885);
FORCEPROP 2 LASTPIN (-3350 825) $PN M61
J 0
(-3340 835);
DISPLAY 0.617021 (-3340 835);
PAINT ORANGE (-3340 835);
FORCEPROP 2 LASTPIN (-3350 775) $PN K55
J 0
(-3340 785);
DISPLAY 0.617021 (-3340 785);
PAINT ORANGE (-3340 785);
FORCEPROP 2 LASTPIN (-3350 725) $PN T53
J 0
(-3340 735);
DISPLAY 0.617021 (-3340 735);
PAINT ORANGE (-3340 735);
FORCEPROP 2 LASTPIN (-3350 575) $PN W62
J 0
(-3340 585);
DISPLAY 0.617021 (-3340 585);
PAINT ORANGE (-3340 585);
FORCEPROP 2 LASTPIN (-3350 625) $PN T63
J 0
(-3340 635);
DISPLAY 0.617021 (-3340 635);
PAINT ORANGE (-3340 635);
FORCEPROP 2 LASTPIN (-5050 2925) $PN F75
J 2
(-5060 2935);
DISPLAY 0.617021 (-5060 2935);
PAINT ORANGE (-5060 2935);
FORCEPROP 2 LASTPIN (-5050 2875) $PN F71
J 2
(-5060 2885);
DISPLAY 0.617021 (-5060 2885);
PAINT ORANGE (-5060 2885);
FORCEPROP 1 LAST PACK_TYPE BGA1
J 0
(-5000 4975);
PAINT SKYBLUE (-5000 4975);
DISPLAY INVISIBLE (-5000 4975);
FORCEPROP 2 LAST SEC_TYPE BGA1
J 0
(-5000 4975);
DISPLAY 1.021277 (-5000 4975);
PAINT ORANGE (-5000 4975);
DISPLAY INVISIBLE (-5000 4975);
FORCEPROP 2 LAST CDS_LIB chpset_lib
J 0
(-4200 2575);
PAINT ORANGE (-4200 2575);
DISPLAY INVISIBLE (-4200 2575);
FORCEPROP 2 LAST SEC 4
J 0
(-5000 4975);
DISPLAY 0.680851 (-5000 4975);
PAINT MONO (-5000 4975);
DISPLAY INVISIBLE (-5000 4975);
FORCEPROP 2 LAST CDS_LOCATION U2D1
J 0
(-5000 4925);
DISPLAY 0.617021 (-5000 4925);
PAINT AQUA (-5000 4925);
DISPLAY INVISIBLE (-5000 4925);
FORCEPROP 1 LAST PATH I172
J 0
(-4200 4875);
PAINT GREEN (-4200 4875);
DISPLAY INVISIBLE (-4200 4875);
FORCEADD TAP..6
(-5600 1325);
FORCEPROP 3 LASTPIN (-5550 1325) SIG_NAME M_H_ECC<5>
J 0
(-5540 1335);
DISPLAY 0.659574 (-5540 1335);
PAINT MONO (-5540 1335);
DISPLAY INVISIBLE (-5540 1335);
FORCEPROP 1 LASTPIN (-5550 1325) BN 5
J 0
(-5602 1333);
DISPLAY 0.617021 (-5602 1333);
PAINT GREEN (-5602 1333);
FORCEPROP 2 LAST CDS_LIB mstr_standard
J 0
(-5600 1325);
PAINT MONO (-5600 1325);
DISPLAY INVISIBLE (-5600 1325);
FORCEPROP 1 LAST BODY_TYPE PLUMBING
J 0
(-5600 1275);
DISPLAY 1.595745 (-5600 1275);
PAINT GREEN (-5600 1275);
DISPLAY INVISIBLE (-5600 1275);
FORCEPROP 1 LAST HDL_TAP TRUE
J 0
(-5275 1200);
DISPLAY 1.595745 (-5275 1200);
PAINT GREEN (-5275 1200);
DISPLAY INVISIBLE (-5275 1200);
FORCEPROP 1 LAST PATH I18
J 0
(-5602 1325);
DISPLAY 0.872340 (-5602 1325);
PAINT GREEN (-5602 1325);
DISPLAY INVISIBLE (-5602 1325);
FORCEADD TAP..6
(-5600 1375);
FORCEPROP 3 LASTPIN (-5550 1375) SIG_NAME M_H_ECC<6>
J 0
(-5540 1385);
DISPLAY 0.659574 (-5540 1385);
PAINT MONO (-5540 1385);
DISPLAY INVISIBLE (-5540 1385);
FORCEPROP 1 LASTPIN (-5550 1375) BN 6
J 0
(-5602 1383);
DISPLAY 0.617021 (-5602 1383);
PAINT GREEN (-5602 1383);
FORCEPROP 2 LAST CDS_LIB mstr_standard
J 0
(-5600 1375);
PAINT MONO (-5600 1375);
DISPLAY INVISIBLE (-5600 1375);
FORCEPROP 1 LAST BODY_TYPE PLUMBING
J 0
(-5600 1325);
DISPLAY 1.595745 (-5600 1325);
PAINT GREEN (-5600 1325);
DISPLAY INVISIBLE (-5600 1325);
FORCEPROP 1 LAST HDL_TAP TRUE
J 0
(-5275 1250);
DISPLAY 1.595745 (-5275 1250);
PAINT GREEN (-5275 1250);
DISPLAY INVISIBLE (-5275 1250);
FORCEPROP 1 LAST PATH I19
J 0
(-5602 1375);
DISPLAY 0.872340 (-5602 1375);
PAINT GREEN (-5602 1375);
DISPLAY INVISIBLE (-5602 1375);
FORCEADD OFFPAGE..5
(-6450 825);
FORCEPROP 2 LAST $XR1 80 
J 0
(-6764 825);
DISPLAY 0.638298 (-6764 825);
PAINT MONO (-6764 825);
FORCEPROP 2 LAST $XR0 79 
J 0
(-6674 825);
DISPLAY 0.638298 (-6674 825);
PAINT MONO (-6674 825);
FORCEPROP 2 LAST CDS_LIB mstr_standard
J 0
(-6450 825);
PAINT MONO (-6450 825);
DISPLAY INVISIBLE (-6450 825);
FORCEPROP 1 LAST OFFPAGE TRUE
J 0
(-6125 700);
DISPLAY 1.170213 (-6125 700);
PAINT GREEN (-6125 700);
DISPLAY INVISIBLE (-6125 700);
FORCEPROP 1 LAST COMMENT_BODY TRUE
J 0
(-6350 750);
DISPLAY 1.170213 (-6350 750);
PAINT GREEN (-6350 750);
DISPLAY INVISIBLE (-6350 750);
FORCEPROP 2 LAST PATH I2
J 0
(-6400 900);
DISPLAY 1.021277 (-6400 900);
PAINT ORANGE (-6400 900);
DISPLAY INVISIBLE (-6400 900);
FORCEADD TAP..6
(-5600 1425);
FORCEPROP 3 LASTPIN (-5550 1425) SIG_NAME M_H_ECC<7>
J 0
(-5540 1435);
DISPLAY 0.659574 (-5540 1435);
PAINT MONO (-5540 1435);
DISPLAY INVISIBLE (-5540 1435);
FORCEPROP 1 LASTPIN (-5550 1425) BN 7
J 0
(-5602 1433);
DISPLAY 0.617021 (-5602 1433);
PAINT GREEN (-5602 1433);
FORCEPROP 2 LAST CDS_LIB mstr_standard
J 0
(-5600 1425);
PAINT MONO (-5600 1425);
DISPLAY INVISIBLE (-5600 1425);
FORCEPROP 1 LAST BODY_TYPE PLUMBING
J 0
(-5600 1375);
DISPLAY 1.595745 (-5600 1375);
PAINT GREEN (-5600 1375);
DISPLAY INVISIBLE (-5600 1375);
FORCEPROP 1 LAST HDL_TAP TRUE
J 0
(-5275 1300);
DISPLAY 1.595745 (-5275 1300);
PAINT GREEN (-5275 1300);
DISPLAY INVISIBLE (-5275 1300);
FORCEPROP 1 LAST PATH I20
J 0
(-5602 1425);
DISPLAY 0.872340 (-5602 1425);
PAINT GREEN (-5602 1425);
DISPLAY INVISIBLE (-5602 1425);
FORCEADD TAP..6
(-5600 1525);
FORCEPROP 3 LASTPIN (-5550 1525) SIG_NAME M_H_DQ<0>
J 0
(-5540 1535);
DISPLAY 0.659574 (-5540 1535);
PAINT MONO (-5540 1535);
DISPLAY INVISIBLE (-5540 1535);
FORCEPROP 1 LASTPIN (-5550 1525) BN 0
J 0
(-5602 1533);
DISPLAY 0.617021 (-5602 1533);
PAINT GREEN (-5602 1533);
FORCEPROP 2 LAST CDS_LIB mstr_standard
J 0
(-5600 1525);
PAINT MONO (-5600 1525);
DISPLAY INVISIBLE (-5600 1525);
FORCEPROP 1 LAST BODY_TYPE PLUMBING
J 0
(-5600 1475);
DISPLAY 1.595745 (-5600 1475);
PAINT GREEN (-5600 1475);
DISPLAY INVISIBLE (-5600 1475);
FORCEPROP 1 LAST HDL_TAP TRUE
J 0
(-5275 1400);
DISPLAY 1.595745 (-5275 1400);
PAINT GREEN (-5275 1400);
DISPLAY INVISIBLE (-5275 1400);
FORCEPROP 1 LAST PATH I21
J 0
(-5602 1525);
DISPLAY 0.872340 (-5602 1525);
PAINT GREEN (-5602 1525);
DISPLAY INVISIBLE (-5602 1525);
FORCEADD TAP..6
(-5600 1575);
FORCEPROP 3 LASTPIN (-5550 1575) SIG_NAME M_H_DQ<1>
J 0
(-5540 1585);
DISPLAY 0.659574 (-5540 1585);
PAINT MONO (-5540 1585);
DISPLAY INVISIBLE (-5540 1585);
FORCEPROP 1 LASTPIN (-5550 1575) BN 1
J 0
(-5602 1583);
DISPLAY 0.617021 (-5602 1583);
PAINT GREEN (-5602 1583);
FORCEPROP 2 LAST CDS_LIB mstr_standard
J 0
(-5600 1575);
PAINT MONO (-5600 1575);
DISPLAY INVISIBLE (-5600 1575);
FORCEPROP 1 LAST BODY_TYPE PLUMBING
J 0
(-5600 1525);
DISPLAY 1.595745 (-5600 1525);
PAINT GREEN (-5600 1525);
DISPLAY INVISIBLE (-5600 1525);
FORCEPROP 1 LAST HDL_TAP TRUE
J 0
(-5275 1450);
DISPLAY 1.595745 (-5275 1450);
PAINT GREEN (-5275 1450);
DISPLAY INVISIBLE (-5275 1450);
FORCEPROP 1 LAST PATH I22
J 0
(-5602 1575);
DISPLAY 0.872340 (-5602 1575);
PAINT GREEN (-5602 1575);
DISPLAY INVISIBLE (-5602 1575);
FORCEADD TAP..6
(-5600 1625);
FORCEPROP 3 LASTPIN (-5550 1625) SIG_NAME M_H_DQ<2>
J 0
(-5540 1635);
DISPLAY 0.659574 (-5540 1635);
PAINT MONO (-5540 1635);
DISPLAY INVISIBLE (-5540 1635);
FORCEPROP 1 LASTPIN (-5550 1625) BN 2
J 0
(-5602 1633);
DISPLAY 0.617021 (-5602 1633);
PAINT GREEN (-5602 1633);
FORCEPROP 2 LAST CDS_LIB mstr_standard
J 0
(-5600 1625);
PAINT MONO (-5600 1625);
DISPLAY INVISIBLE (-5600 1625);
FORCEPROP 1 LAST BODY_TYPE PLUMBING
J 0
(-5600 1575);
DISPLAY 1.595745 (-5600 1575);
PAINT GREEN (-5600 1575);
DISPLAY INVISIBLE (-5600 1575);
FORCEPROP 1 LAST HDL_TAP TRUE
J 0
(-5275 1500);
DISPLAY 1.595745 (-5275 1500);
PAINT GREEN (-5275 1500);
DISPLAY INVISIBLE (-5275 1500);
FORCEPROP 1 LAST PATH I23
J 0
(-5602 1625);
DISPLAY 0.872340 (-5602 1625);
PAINT GREEN (-5602 1625);
DISPLAY INVISIBLE (-5602 1625);
FORCEADD TAP..6
(-5600 1675);
FORCEPROP 3 LASTPIN (-5550 1675) SIG_NAME M_H_DQ<3>
J 0
(-5540 1685);
DISPLAY 0.659574 (-5540 1685);
PAINT MONO (-5540 1685);
DISPLAY INVISIBLE (-5540 1685);
FORCEPROP 1 LASTPIN (-5550 1675) BN 3
J 0
(-5602 1683);
DISPLAY 0.617021 (-5602 1683);
PAINT GREEN (-5602 1683);
FORCEPROP 2 LAST CDS_LIB mstr_standard
J 0
(-5600 1675);
PAINT MONO (-5600 1675);
DISPLAY INVISIBLE (-5600 1675);
FORCEPROP 1 LAST BODY_TYPE PLUMBING
J 0
(-5600 1625);
DISPLAY 1.595745 (-5600 1625);
PAINT GREEN (-5600 1625);
DISPLAY INVISIBLE (-5600 1625);
FORCEPROP 1 LAST HDL_TAP TRUE
J 0
(-5275 1550);
DISPLAY 1.595745 (-5275 1550);
PAINT GREEN (-5275 1550);
DISPLAY INVISIBLE (-5275 1550);
FORCEPROP 1 LAST PATH I24
J 0
(-5602 1675);
DISPLAY 0.872340 (-5602 1675);
PAINT GREEN (-5602 1675);
DISPLAY INVISIBLE (-5602 1675);
FORCEADD TAP..6
(-5600 1725);
FORCEPROP 3 LASTPIN (-5550 1725) SIG_NAME M_H_DQ<4>
J 0
(-5540 1735);
DISPLAY 0.659574 (-5540 1735);
PAINT MONO (-5540 1735);
DISPLAY INVISIBLE (-5540 1735);
FORCEPROP 1 LASTPIN (-5550 1725) BN 4
J 0
(-5602 1733);
DISPLAY 0.617021 (-5602 1733);
PAINT GREEN (-5602 1733);
FORCEPROP 2 LAST CDS_LIB mstr_standard
J 0
(-5600 1725);
PAINT MONO (-5600 1725);
DISPLAY INVISIBLE (-5600 1725);
FORCEPROP 1 LAST BODY_TYPE PLUMBING
J 0
(-5600 1675);
DISPLAY 1.595745 (-5600 1675);
PAINT GREEN (-5600 1675);
DISPLAY INVISIBLE (-5600 1675);
FORCEPROP 1 LAST HDL_TAP TRUE
J 0
(-5275 1600);
DISPLAY 1.595745 (-5275 1600);
PAINT GREEN (-5275 1600);
DISPLAY INVISIBLE (-5275 1600);
FORCEPROP 1 LAST PATH I25
J 0
(-5602 1725);
DISPLAY 0.872340 (-5602 1725);
PAINT GREEN (-5602 1725);
DISPLAY INVISIBLE (-5602 1725);
FORCEADD TAP..6
(-5600 1775);
FORCEPROP 3 LASTPIN (-5550 1775) SIG_NAME M_H_DQ<5>
J 0
(-5540 1785);
DISPLAY 0.659574 (-5540 1785);
PAINT MONO (-5540 1785);
DISPLAY INVISIBLE (-5540 1785);
FORCEPROP 1 LASTPIN (-5550 1775) BN 5
J 0
(-5602 1783);
DISPLAY 0.617021 (-5602 1783);
PAINT GREEN (-5602 1783);
FORCEPROP 2 LAST CDS_LIB mstr_standard
J 0
(-5600 1775);
PAINT MONO (-5600 1775);
DISPLAY INVISIBLE (-5600 1775);
FORCEPROP 1 LAST BODY_TYPE PLUMBING
J 0
(-5600 1725);
DISPLAY 1.595745 (-5600 1725);
PAINT GREEN (-5600 1725);
DISPLAY INVISIBLE (-5600 1725);
FORCEPROP 1 LAST HDL_TAP TRUE
J 0
(-5275 1650);
DISPLAY 1.595745 (-5275 1650);
PAINT GREEN (-5275 1650);
DISPLAY INVISIBLE (-5275 1650);
FORCEPROP 1 LAST PATH I26
J 0
(-5602 1775);
DISPLAY 0.872340 (-5602 1775);
PAINT GREEN (-5602 1775);
DISPLAY INVISIBLE (-5602 1775);
FORCEADD TAP..6
(-5600 1825);
FORCEPROP 3 LASTPIN (-5550 1825) SIG_NAME M_H_DQ<6>
J 0
(-5540 1835);
DISPLAY 0.659574 (-5540 1835);
PAINT MONO (-5540 1835);
DISPLAY INVISIBLE (-5540 1835);
FORCEPROP 1 LASTPIN (-5550 1825) BN 6
J 0
(-5602 1833);
DISPLAY 0.617021 (-5602 1833);
PAINT GREEN (-5602 1833);
FORCEPROP 2 LAST CDS_LIB mstr_standard
J 0
(-5600 1825);
PAINT MONO (-5600 1825);
DISPLAY INVISIBLE (-5600 1825);
FORCEPROP 1 LAST BODY_TYPE PLUMBING
J 0
(-5600 1775);
DISPLAY 1.595745 (-5600 1775);
PAINT GREEN (-5600 1775);
DISPLAY INVISIBLE (-5600 1775);
FORCEPROP 1 LAST HDL_TAP TRUE
J 0
(-5275 1700);
DISPLAY 1.595745 (-5275 1700);
PAINT GREEN (-5275 1700);
DISPLAY INVISIBLE (-5275 1700);
FORCEPROP 1 LAST PATH I27
J 0
(-5602 1825);
DISPLAY 0.872340 (-5602 1825);
PAINT GREEN (-5602 1825);
DISPLAY INVISIBLE (-5602 1825);
FORCEADD TAP..6
(-5600 1925);
FORCEPROP 3 LASTPIN (-5550 1925) SIG_NAME M_H_DQ<8>
J 0
(-5540 1935);
DISPLAY 0.659574 (-5540 1935);
PAINT MONO (-5540 1935);
DISPLAY INVISIBLE (-5540 1935);
FORCEPROP 1 LASTPIN (-5550 1925) BN 8
J 0
(-5602 1933);
DISPLAY 0.617021 (-5602 1933);
PAINT GREEN (-5602 1933);
FORCEPROP 2 LAST CDS_LIB mstr_standard
J 0
(-5600 1925);
PAINT MONO (-5600 1925);
DISPLAY INVISIBLE (-5600 1925);
FORCEPROP 1 LAST BODY_TYPE PLUMBING
J 0
(-5600 1875);
DISPLAY 1.595745 (-5600 1875);
PAINT GREEN (-5600 1875);
DISPLAY INVISIBLE (-5600 1875);
FORCEPROP 1 LAST HDL_TAP TRUE
J 0
(-5275 1800);
DISPLAY 1.595745 (-5275 1800);
PAINT GREEN (-5275 1800);
DISPLAY INVISIBLE (-5275 1800);
FORCEPROP 1 LAST PATH I28
J 0
(-5602 1925);
DISPLAY 0.872340 (-5602 1925);
PAINT GREEN (-5602 1925);
DISPLAY INVISIBLE (-5602 1925);
FORCEADD TAP..6
(-5600 1875);
FORCEPROP 3 LASTPIN (-5550 1875) SIG_NAME M_H_DQ<7>
J 0
(-5540 1885);
DISPLAY 0.659574 (-5540 1885);
PAINT MONO (-5540 1885);
DISPLAY INVISIBLE (-5540 1885);
FORCEPROP 1 LASTPIN (-5550 1875) BN 7
J 0
(-5602 1883);
DISPLAY 0.617021 (-5602 1883);
PAINT GREEN (-5602 1883);
FORCEPROP 2 LAST CDS_LIB mstr_standard
J 0
(-5600 1875);
PAINT MONO (-5600 1875);
DISPLAY INVISIBLE (-5600 1875);
FORCEPROP 1 LAST BODY_TYPE PLUMBING
J 0
(-5600 1825);
DISPLAY 1.595745 (-5600 1825);
PAINT GREEN (-5600 1825);
DISPLAY INVISIBLE (-5600 1825);
FORCEPROP 1 LAST HDL_TAP TRUE
J 0
(-5275 1750);
DISPLAY 1.595745 (-5275 1750);
PAINT GREEN (-5275 1750);
DISPLAY INVISIBLE (-5275 1750);
FORCEPROP 1 LAST PATH I29
J 0
(-5602 1875);
DISPLAY 0.872340 (-5602 1875);
PAINT GREEN (-5602 1875);
DISPLAY INVISIBLE (-5602 1875);
FORCEADD OFFPAGE..5
(-6450 1025);
FORCEPROP 2 LAST $XR1 80 
J 0
(-6764 1025);
DISPLAY 0.638298 (-6764 1025);
PAINT MONO (-6764 1025);
FORCEPROP 2 LAST $XR0 79 
J 0
(-6674 1025);
DISPLAY 0.638298 (-6674 1025);
PAINT MONO (-6674 1025);
FORCEPROP 2 LAST CDS_LIB mstr_standard
J 0
(-6450 1025);
PAINT MONO (-6450 1025);
DISPLAY INVISIBLE (-6450 1025);
FORCEPROP 1 LAST OFFPAGE TRUE
J 0
(-6125 900);
DISPLAY 1.170213 (-6125 900);
PAINT GREEN (-6125 900);
DISPLAY INVISIBLE (-6125 900);
FORCEPROP 1 LAST COMMENT_BODY TRUE
J 0
(-6350 950);
DISPLAY 1.170213 (-6350 950);
PAINT GREEN (-6350 950);
DISPLAY INVISIBLE (-6350 950);
FORCEPROP 2 LAST PATH I3
J 0
(-6400 1100);
DISPLAY 1.021277 (-6400 1100);
PAINT ORANGE (-6400 1100);
DISPLAY INVISIBLE (-6400 1100);
FORCEADD TAP..6
(-5600 1975);
FORCEPROP 3 LASTPIN (-5550 1975) SIG_NAME M_H_DQ<9>
J 0
(-5540 1985);
DISPLAY 0.659574 (-5540 1985);
PAINT MONO (-5540 1985);
DISPLAY INVISIBLE (-5540 1985);
FORCEPROP 1 LASTPIN (-5550 1975) BN 9
J 0
(-5602 1983);
DISPLAY 0.617021 (-5602 1983);
PAINT GREEN (-5602 1983);
FORCEPROP 2 LAST CDS_LIB mstr_standard
J 0
(-5600 1975);
PAINT MONO (-5600 1975);
DISPLAY INVISIBLE (-5600 1975);
FORCEPROP 1 LAST BODY_TYPE PLUMBING
J 0
(-5600 1925);
DISPLAY 1.595745 (-5600 1925);
PAINT GREEN (-5600 1925);
DISPLAY INVISIBLE (-5600 1925);
FORCEPROP 1 LAST HDL_TAP TRUE
J 0
(-5275 1850);
DISPLAY 1.595745 (-5275 1850);
PAINT GREEN (-5275 1850);
DISPLAY INVISIBLE (-5275 1850);
FORCEPROP 1 LAST PATH I31
J 0
(-5602 1975);
DISPLAY 0.872340 (-5602 1975);
PAINT GREEN (-5602 1975);
DISPLAY INVISIBLE (-5602 1975);
FORCEADD TAP..6
(-5600 2025);
FORCEPROP 3 LASTPIN (-5550 2025) SIG_NAME M_H_DQ<10>
J 0
(-5540 2035);
DISPLAY 0.659574 (-5540 2035);
PAINT MONO (-5540 2035);
DISPLAY INVISIBLE (-5540 2035);
FORCEPROP 1 LASTPIN (-5550 2025) BN 10
J 0
(-5602 2033);
DISPLAY 0.617021 (-5602 2033);
PAINT GREEN (-5602 2033);
FORCEPROP 2 LAST CDS_LIB mstr_standard
J 0
(-5600 2025);
PAINT MONO (-5600 2025);
DISPLAY INVISIBLE (-5600 2025);
FORCEPROP 1 LAST BODY_TYPE PLUMBING
J 0
(-5600 1975);
DISPLAY 1.595745 (-5600 1975);
PAINT GREEN (-5600 1975);
DISPLAY INVISIBLE (-5600 1975);
FORCEPROP 1 LAST HDL_TAP TRUE
J 0
(-5275 1900);
DISPLAY 1.595745 (-5275 1900);
PAINT GREEN (-5275 1900);
DISPLAY INVISIBLE (-5275 1900);
FORCEPROP 1 LAST PATH I32
J 0
(-5602 2025);
DISPLAY 0.872340 (-5602 2025);
PAINT GREEN (-5602 2025);
DISPLAY INVISIBLE (-5602 2025);
FORCEADD TAP..6
(-5600 2075);
FORCEPROP 3 LASTPIN (-5550 2075) SIG_NAME M_H_DQ<11>
J 0
(-5540 2085);
DISPLAY 0.659574 (-5540 2085);
PAINT MONO (-5540 2085);
DISPLAY INVISIBLE (-5540 2085);
FORCEPROP 1 LASTPIN (-5550 2075) BN 11
J 0
(-5602 2083);
DISPLAY 0.617021 (-5602 2083);
PAINT GREEN (-5602 2083);
FORCEPROP 2 LAST CDS_LIB mstr_standard
J 0
(-5600 2075);
PAINT MONO (-5600 2075);
DISPLAY INVISIBLE (-5600 2075);
FORCEPROP 1 LAST BODY_TYPE PLUMBING
J 0
(-5600 2025);
DISPLAY 1.595745 (-5600 2025);
PAINT GREEN (-5600 2025);
DISPLAY INVISIBLE (-5600 2025);
FORCEPROP 1 LAST HDL_TAP TRUE
J 0
(-5275 1950);
DISPLAY 1.595745 (-5275 1950);
PAINT GREEN (-5275 1950);
DISPLAY INVISIBLE (-5275 1950);
FORCEPROP 1 LAST PATH I33
J 0
(-5602 2075);
DISPLAY 0.872340 (-5602 2075);
PAINT GREEN (-5602 2075);
DISPLAY INVISIBLE (-5602 2075);
FORCEADD TAP..6
(-5600 2125);
FORCEPROP 3 LASTPIN (-5550 2125) SIG_NAME M_H_DQ<12>
J 0
(-5540 2135);
DISPLAY 0.659574 (-5540 2135);
PAINT MONO (-5540 2135);
DISPLAY INVISIBLE (-5540 2135);
FORCEPROP 1 LASTPIN (-5550 2125) BN 12
J 0
(-5602 2133);
DISPLAY 0.617021 (-5602 2133);
PAINT GREEN (-5602 2133);
FORCEPROP 2 LAST CDS_LIB mstr_standard
J 0
(-5600 2125);
PAINT MONO (-5600 2125);
DISPLAY INVISIBLE (-5600 2125);
FORCEPROP 1 LAST BODY_TYPE PLUMBING
J 0
(-5600 2075);
DISPLAY 1.595745 (-5600 2075);
PAINT GREEN (-5600 2075);
DISPLAY INVISIBLE (-5600 2075);
FORCEPROP 1 LAST HDL_TAP TRUE
J 0
(-5275 2000);
DISPLAY 1.595745 (-5275 2000);
PAINT GREEN (-5275 2000);
DISPLAY INVISIBLE (-5275 2000);
FORCEPROP 1 LAST PATH I34
J 0
(-5602 2125);
DISPLAY 0.872340 (-5602 2125);
PAINT GREEN (-5602 2125);
DISPLAY INVISIBLE (-5602 2125);
FORCEADD TAP..6
(-5600 2175);
FORCEPROP 3 LASTPIN (-5550 2175) SIG_NAME M_H_DQ<13>
J 0
(-5540 2185);
DISPLAY 0.659574 (-5540 2185);
PAINT MONO (-5540 2185);
DISPLAY INVISIBLE (-5540 2185);
FORCEPROP 1 LASTPIN (-5550 2175) BN 13
J 0
(-5602 2183);
DISPLAY 0.617021 (-5602 2183);
PAINT GREEN (-5602 2183);
FORCEPROP 2 LAST CDS_LIB mstr_standard
J 0
(-5600 2175);
PAINT MONO (-5600 2175);
DISPLAY INVISIBLE (-5600 2175);
FORCEPROP 1 LAST BODY_TYPE PLUMBING
J 0
(-5600 2125);
DISPLAY 1.595745 (-5600 2125);
PAINT GREEN (-5600 2125);
DISPLAY INVISIBLE (-5600 2125);
FORCEPROP 1 LAST HDL_TAP TRUE
J 0
(-5275 2050);
DISPLAY 1.595745 (-5275 2050);
PAINT GREEN (-5275 2050);
DISPLAY INVISIBLE (-5275 2050);
FORCEPROP 1 LAST PATH I35
J 0
(-5602 2175);
DISPLAY 0.872340 (-5602 2175);
PAINT GREEN (-5602 2175);
DISPLAY INVISIBLE (-5602 2175);
FORCEADD TAP..6
(-5600 2225);
FORCEPROP 3 LASTPIN (-5550 2225) SIG_NAME M_H_DQ<14>
J 0
(-5540 2235);
DISPLAY 0.659574 (-5540 2235);
PAINT MONO (-5540 2235);
DISPLAY INVISIBLE (-5540 2235);
FORCEPROP 1 LASTPIN (-5550 2225) BN 14
J 0
(-5602 2233);
DISPLAY 0.617021 (-5602 2233);
PAINT GREEN (-5602 2233);
FORCEPROP 2 LAST CDS_LIB mstr_standard
J 0
(-5600 2225);
PAINT MONO (-5600 2225);
DISPLAY INVISIBLE (-5600 2225);
FORCEPROP 1 LAST BODY_TYPE PLUMBING
J 0
(-5600 2175);
DISPLAY 1.595745 (-5600 2175);
PAINT GREEN (-5600 2175);
DISPLAY INVISIBLE (-5600 2175);
FORCEPROP 1 LAST HDL_TAP TRUE
J 0
(-5275 2100);
DISPLAY 1.595745 (-5275 2100);
PAINT GREEN (-5275 2100);
DISPLAY INVISIBLE (-5275 2100);
FORCEPROP 1 LAST PATH I36
J 0
(-5602 2225);
DISPLAY 0.872340 (-5602 2225);
PAINT GREEN (-5602 2225);
DISPLAY INVISIBLE (-5602 2225);
FORCEADD TAP..6
(-5600 2275);
FORCEPROP 3 LASTPIN (-5550 2275) SIG_NAME M_H_DQ<15>
J 0
(-5540 2285);
DISPLAY 0.659574 (-5540 2285);
PAINT MONO (-5540 2285);
DISPLAY INVISIBLE (-5540 2285);
FORCEPROP 1 LASTPIN (-5550 2275) BN 15
J 0
(-5602 2283);
DISPLAY 0.617021 (-5602 2283);
PAINT GREEN (-5602 2283);
FORCEPROP 2 LAST CDS_LIB mstr_standard
J 0
(-5600 2275);
PAINT MONO (-5600 2275);
DISPLAY INVISIBLE (-5600 2275);
FORCEPROP 1 LAST BODY_TYPE PLUMBING
J 0
(-5600 2225);
DISPLAY 1.595745 (-5600 2225);
PAINT GREEN (-5600 2225);
DISPLAY INVISIBLE (-5600 2225);
FORCEPROP 1 LAST HDL_TAP TRUE
J 0
(-5275 2150);
DISPLAY 1.595745 (-5275 2150);
PAINT GREEN (-5275 2150);
DISPLAY INVISIBLE (-5275 2150);
FORCEPROP 1 LAST PATH I37
J 0
(-5602 2275);
DISPLAY 0.872340 (-5602 2275);
PAINT GREEN (-5602 2275);
DISPLAY INVISIBLE (-5602 2275);
FORCEADD TAP..6
(-5600 2325);
FORCEPROP 3 LASTPIN (-5550 2325) SIG_NAME M_H_DQ<16>
J 0
(-5540 2335);
DISPLAY 0.659574 (-5540 2335);
PAINT MONO (-5540 2335);
DISPLAY INVISIBLE (-5540 2335);
FORCEPROP 1 LASTPIN (-5550 2325) BN 16
J 0
(-5602 2333);
DISPLAY 0.617021 (-5602 2333);
PAINT GREEN (-5602 2333);
FORCEPROP 2 LAST CDS_LIB mstr_standard
J 0
(-5600 2325);
PAINT MONO (-5600 2325);
DISPLAY INVISIBLE (-5600 2325);
FORCEPROP 1 LAST BODY_TYPE PLUMBING
J 0
(-5600 2275);
DISPLAY 1.595745 (-5600 2275);
PAINT GREEN (-5600 2275);
DISPLAY INVISIBLE (-5600 2275);
FORCEPROP 1 LAST HDL_TAP TRUE
J 0
(-5275 2200);
DISPLAY 1.595745 (-5275 2200);
PAINT GREEN (-5275 2200);
DISPLAY INVISIBLE (-5275 2200);
FORCEPROP 1 LAST PATH I38
J 0
(-5602 2325);
DISPLAY 0.872340 (-5602 2325);
PAINT GREEN (-5602 2325);
DISPLAY INVISIBLE (-5602 2325);
FORCEADD TAP..6
(-5600 2375);
FORCEPROP 3 LASTPIN (-5550 2375) SIG_NAME M_H_DQ<17>
J 0
(-5540 2385);
DISPLAY 0.659574 (-5540 2385);
PAINT MONO (-5540 2385);
DISPLAY INVISIBLE (-5540 2385);
FORCEPROP 1 LASTPIN (-5550 2375) BN 17
J 0
(-5602 2383);
DISPLAY 0.617021 (-5602 2383);
PAINT GREEN (-5602 2383);
FORCEPROP 2 LAST CDS_LIB mstr_standard
J 0
(-5600 2375);
PAINT MONO (-5600 2375);
DISPLAY INVISIBLE (-5600 2375);
FORCEPROP 1 LAST BODY_TYPE PLUMBING
J 0
(-5600 2325);
DISPLAY 1.595745 (-5600 2325);
PAINT GREEN (-5600 2325);
DISPLAY INVISIBLE (-5600 2325);
FORCEPROP 1 LAST HDL_TAP TRUE
J 0
(-5275 2250);
DISPLAY 1.595745 (-5275 2250);
PAINT GREEN (-5275 2250);
DISPLAY INVISIBLE (-5275 2250);
FORCEPROP 1 LAST PATH I39
J 0
(-5602 2375);
DISPLAY 0.872340 (-5602 2375);
PAINT GREEN (-5602 2375);
DISPLAY INVISIBLE (-5602 2375);
FORCEADD OFFPAGE..6
(-6450 1475);
FORCEPROP 2 LAST $XR1 80 
J 0
(-6789 1475);
DISPLAY 0.638298 (-6789 1475);
PAINT MONO (-6789 1475);
FORCEPROP 2 LAST $XR0 79 
J 0
(-6699 1475);
DISPLAY 0.638298 (-6699 1475);
PAINT MONO (-6699 1475);
FORCEPROP 2 LAST CDS_LIB mstr_standard
J 0
(-6450 1475);
PAINT MONO (-6450 1475);
DISPLAY INVISIBLE (-6450 1475);
FORCEPROP 1 LAST OFFPAGE TRUE
J 0
(-6125 1350);
DISPLAY 1.170213 (-6125 1350);
PAINT GREEN (-6125 1350);
DISPLAY INVISIBLE (-6125 1350);
FORCEPROP 1 LAST COMMENT_BODY TRUE
J 0
(-6350 1400);
DISPLAY 1.170213 (-6350 1400);
PAINT GREEN (-6350 1400);
DISPLAY INVISIBLE (-6350 1400);
FORCEPROP 2 LAST PATH I4
J 0
(-6400 1550);
DISPLAY 1.021277 (-6400 1550);
PAINT ORANGE (-6400 1550);
DISPLAY INVISIBLE (-6400 1550);
FORCEADD TAP..6
(-5600 2425);
FORCEPROP 3 LASTPIN (-5550 2425) SIG_NAME M_H_DQ<18>
J 0
(-5540 2435);
DISPLAY 0.659574 (-5540 2435);
PAINT MONO (-5540 2435);
DISPLAY INVISIBLE (-5540 2435);
FORCEPROP 1 LASTPIN (-5550 2425) BN 18
J 0
(-5602 2433);
DISPLAY 0.617021 (-5602 2433);
PAINT GREEN (-5602 2433);
FORCEPROP 2 LAST CDS_LIB mstr_standard
J 0
(-5600 2425);
PAINT MONO (-5600 2425);
DISPLAY INVISIBLE (-5600 2425);
FORCEPROP 1 LAST BODY_TYPE PLUMBING
J 0
(-5600 2375);
DISPLAY 1.595745 (-5600 2375);
PAINT GREEN (-5600 2375);
DISPLAY INVISIBLE (-5600 2375);
FORCEPROP 1 LAST HDL_TAP TRUE
J 0
(-5275 2300);
DISPLAY 1.595745 (-5275 2300);
PAINT GREEN (-5275 2300);
DISPLAY INVISIBLE (-5275 2300);
FORCEPROP 1 LAST PATH I40
J 0
(-5602 2425);
DISPLAY 0.872340 (-5602 2425);
PAINT GREEN (-5602 2425);
DISPLAY INVISIBLE (-5602 2425);
FORCEADD TAP..6
(-5600 2475);
FORCEPROP 3 LASTPIN (-5550 2475) SIG_NAME M_H_DQ<19>
J 0
(-5540 2485);
DISPLAY 0.659574 (-5540 2485);
PAINT MONO (-5540 2485);
DISPLAY INVISIBLE (-5540 2485);
FORCEPROP 1 LASTPIN (-5550 2475) BN 19
J 0
(-5602 2483);
DISPLAY 0.617021 (-5602 2483);
PAINT GREEN (-5602 2483);
FORCEPROP 2 LAST CDS_LIB mstr_standard
J 0
(-5600 2475);
PAINT MONO (-5600 2475);
DISPLAY INVISIBLE (-5600 2475);
FORCEPROP 1 LAST BODY_TYPE PLUMBING
J 0
(-5600 2425);
DISPLAY 1.595745 (-5600 2425);
PAINT GREEN (-5600 2425);
DISPLAY INVISIBLE (-5600 2425);
FORCEPROP 1 LAST HDL_TAP TRUE
J 0
(-5275 2350);
DISPLAY 1.595745 (-5275 2350);
PAINT GREEN (-5275 2350);
DISPLAY INVISIBLE (-5275 2350);
FORCEPROP 1 LAST PATH I41
J 0
(-5602 2475);
DISPLAY 0.872340 (-5602 2475);
PAINT GREEN (-5602 2475);
DISPLAY INVISIBLE (-5602 2475);
FORCEADD TAP..6
(-5600 2525);
FORCEPROP 3 LASTPIN (-5550 2525) SIG_NAME M_H_DQ<20>
J 0
(-5540 2535);
DISPLAY 0.659574 (-5540 2535);
PAINT MONO (-5540 2535);
DISPLAY INVISIBLE (-5540 2535);
FORCEPROP 1 LASTPIN (-5550 2525) BN 20
J 0
(-5602 2533);
DISPLAY 0.617021 (-5602 2533);
PAINT GREEN (-5602 2533);
FORCEPROP 2 LAST CDS_LIB mstr_standard
J 0
(-5600 2525);
PAINT MONO (-5600 2525);
DISPLAY INVISIBLE (-5600 2525);
FORCEPROP 1 LAST BODY_TYPE PLUMBING
J 0
(-5600 2475);
DISPLAY 1.595745 (-5600 2475);
PAINT GREEN (-5600 2475);
DISPLAY INVISIBLE (-5600 2475);
FORCEPROP 1 LAST HDL_TAP TRUE
J 0
(-5275 2400);
DISPLAY 1.595745 (-5275 2400);
PAINT GREEN (-5275 2400);
DISPLAY INVISIBLE (-5275 2400);
FORCEPROP 1 LAST PATH I42
J 0
(-5602 2525);
DISPLAY 0.872340 (-5602 2525);
PAINT GREEN (-5602 2525);
DISPLAY INVISIBLE (-5602 2525);
FORCEADD TAP..6
(-5600 2575);
FORCEPROP 3 LASTPIN (-5550 2575) SIG_NAME M_H_DQ<21>
J 0
(-5540 2585);
DISPLAY 0.659574 (-5540 2585);
PAINT MONO (-5540 2585);
DISPLAY INVISIBLE (-5540 2585);
FORCEPROP 1 LASTPIN (-5550 2575) BN 21
J 0
(-5602 2583);
DISPLAY 0.617021 (-5602 2583);
PAINT GREEN (-5602 2583);
FORCEPROP 2 LAST CDS_LIB mstr_standard
J 0
(-5600 2575);
PAINT MONO (-5600 2575);
DISPLAY INVISIBLE (-5600 2575);
FORCEPROP 1 LAST BODY_TYPE PLUMBING
J 0
(-5600 2525);
DISPLAY 1.595745 (-5600 2525);
PAINT GREEN (-5600 2525);
DISPLAY INVISIBLE (-5600 2525);
FORCEPROP 1 LAST HDL_TAP TRUE
J 0
(-5275 2450);
DISPLAY 1.595745 (-5275 2450);
PAINT GREEN (-5275 2450);
DISPLAY INVISIBLE (-5275 2450);
FORCEPROP 1 LAST PATH I43
J 0
(-5602 2575);
DISPLAY 0.872340 (-5602 2575);
PAINT GREEN (-5602 2575);
DISPLAY INVISIBLE (-5602 2575);
FORCEADD TAP..6
(-5600 2625);
FORCEPROP 3 LASTPIN (-5550 2625) SIG_NAME M_H_DQ<22>
J 0
(-5540 2635);
DISPLAY 0.659574 (-5540 2635);
PAINT MONO (-5540 2635);
DISPLAY INVISIBLE (-5540 2635);
FORCEPROP 1 LASTPIN (-5550 2625) BN 22
J 0
(-5602 2633);
DISPLAY 0.617021 (-5602 2633);
PAINT GREEN (-5602 2633);
FORCEPROP 2 LAST CDS_LIB mstr_standard
J 0
(-5600 2625);
PAINT MONO (-5600 2625);
DISPLAY INVISIBLE (-5600 2625);
FORCEPROP 1 LAST BODY_TYPE PLUMBING
J 0
(-5600 2575);
DISPLAY 1.595745 (-5600 2575);
PAINT GREEN (-5600 2575);
DISPLAY INVISIBLE (-5600 2575);
FORCEPROP 1 LAST HDL_TAP TRUE
J 0
(-5275 2500);
DISPLAY 1.595745 (-5275 2500);
PAINT GREEN (-5275 2500);
DISPLAY INVISIBLE (-5275 2500);
FORCEPROP 1 LAST PATH I44
J 0
(-5602 2625);
DISPLAY 0.872340 (-5602 2625);
PAINT GREEN (-5602 2625);
DISPLAY INVISIBLE (-5602 2625);
FORCEADD TAP..6
(-5600 2675);
FORCEPROP 3 LASTPIN (-5550 2675) SIG_NAME M_H_DQ<23>
J 0
(-5540 2685);
DISPLAY 0.659574 (-5540 2685);
PAINT MONO (-5540 2685);
DISPLAY INVISIBLE (-5540 2685);
FORCEPROP 1 LASTPIN (-5550 2675) BN 23
J 0
(-5602 2683);
DISPLAY 0.617021 (-5602 2683);
PAINT GREEN (-5602 2683);
FORCEPROP 2 LAST CDS_LIB mstr_standard
J 0
(-5600 2675);
PAINT MONO (-5600 2675);
DISPLAY INVISIBLE (-5600 2675);
FORCEPROP 1 LAST BODY_TYPE PLUMBING
J 0
(-5600 2625);
DISPLAY 1.595745 (-5600 2625);
PAINT GREEN (-5600 2625);
DISPLAY INVISIBLE (-5600 2625);
FORCEPROP 1 LAST HDL_TAP TRUE
J 0
(-5275 2550);
DISPLAY 1.595745 (-5275 2550);
PAINT GREEN (-5275 2550);
DISPLAY INVISIBLE (-5275 2550);
FORCEPROP 1 LAST PATH I45
J 0
(-5602 2675);
DISPLAY 0.872340 (-5602 2675);
PAINT GREEN (-5602 2675);
DISPLAY INVISIBLE (-5602 2675);
FORCEADD TAP..6
(-5600 2725);
FORCEPROP 3 LASTPIN (-5550 2725) SIG_NAME M_H_DQ<24>
J 0
(-5540 2735);
DISPLAY 0.659574 (-5540 2735);
PAINT MONO (-5540 2735);
DISPLAY INVISIBLE (-5540 2735);
FORCEPROP 1 LASTPIN (-5550 2725) BN 24
J 0
(-5602 2733);
DISPLAY 0.617021 (-5602 2733);
PAINT GREEN (-5602 2733);
FORCEPROP 2 LAST CDS_LIB mstr_standard
J 0
(-5600 2725);
PAINT MONO (-5600 2725);
DISPLAY INVISIBLE (-5600 2725);
FORCEPROP 1 LAST BODY_TYPE PLUMBING
J 0
(-5600 2675);
DISPLAY 1.595745 (-5600 2675);
PAINT GREEN (-5600 2675);
DISPLAY INVISIBLE (-5600 2675);
FORCEPROP 1 LAST HDL_TAP TRUE
J 0
(-5275 2600);
DISPLAY 1.595745 (-5275 2600);
PAINT GREEN (-5275 2600);
DISPLAY INVISIBLE (-5275 2600);
FORCEPROP 1 LAST PATH I46
J 0
(-5602 2725);
DISPLAY 0.872340 (-5602 2725);
PAINT GREEN (-5602 2725);
DISPLAY INVISIBLE (-5602 2725);
FORCEADD TAP..6
(-5600 2825);
FORCEPROP 3 LASTPIN (-5550 2825) SIG_NAME M_H_DQ<26>
J 0
(-5540 2835);
DISPLAY 0.659574 (-5540 2835);
PAINT MONO (-5540 2835);
DISPLAY INVISIBLE (-5540 2835);
FORCEPROP 1 LASTPIN (-5550 2825) BN 26
J 0
(-5602 2833);
DISPLAY 0.617021 (-5602 2833);
PAINT GREEN (-5602 2833);
FORCEPROP 2 LAST CDS_LIB mstr_standard
J 0
(-5600 2825);
PAINT MONO (-5600 2825);
DISPLAY INVISIBLE (-5600 2825);
FORCEPROP 1 LAST BODY_TYPE PLUMBING
J 0
(-5600 2775);
DISPLAY 1.595745 (-5600 2775);
PAINT GREEN (-5600 2775);
DISPLAY INVISIBLE (-5600 2775);
FORCEPROP 1 LAST HDL_TAP TRUE
J 0
(-5275 2700);
DISPLAY 1.595745 (-5275 2700);
PAINT GREEN (-5275 2700);
DISPLAY INVISIBLE (-5275 2700);
FORCEPROP 1 LAST PATH I47
J 0
(-5602 2825);
DISPLAY 0.872340 (-5602 2825);
PAINT GREEN (-5602 2825);
DISPLAY INVISIBLE (-5602 2825);
FORCEADD TAP..6
(-5600 2775);
FORCEPROP 3 LASTPIN (-5550 2775) SIG_NAME M_H_DQ<25>
J 0
(-5540 2785);
DISPLAY 0.659574 (-5540 2785);
PAINT MONO (-5540 2785);
DISPLAY INVISIBLE (-5540 2785);
FORCEPROP 1 LASTPIN (-5550 2775) BN 25
J 0
(-5602 2783);
DISPLAY 0.617021 (-5602 2783);
PAINT GREEN (-5602 2783);
FORCEPROP 2 LAST CDS_LIB mstr_standard
J 0
(-5600 2775);
PAINT MONO (-5600 2775);
DISPLAY INVISIBLE (-5600 2775);
FORCEPROP 1 LAST BODY_TYPE PLUMBING
J 0
(-5600 2725);
DISPLAY 1.595745 (-5600 2725);
PAINT GREEN (-5600 2725);
DISPLAY INVISIBLE (-5600 2725);
FORCEPROP 1 LAST HDL_TAP TRUE
J 0
(-5275 2650);
DISPLAY 1.595745 (-5275 2650);
PAINT GREEN (-5275 2650);
DISPLAY INVISIBLE (-5275 2650);
FORCEPROP 1 LAST PATH I48
J 0
(-5602 2775);
DISPLAY 0.872340 (-5602 2775);
PAINT GREEN (-5602 2775);
DISPLAY INVISIBLE (-5602 2775);
FORCEADD TAP..6
(-5600 2875);
FORCEPROP 3 LASTPIN (-5550 2875) SIG_NAME M_H_DQ<27>
J 0
(-5540 2885);
DISPLAY 0.659574 (-5540 2885);
PAINT MONO (-5540 2885);
DISPLAY INVISIBLE (-5540 2885);
FORCEPROP 1 LASTPIN (-5550 2875) BN 27
J 0
(-5602 2883);
DISPLAY 0.617021 (-5602 2883);
PAINT GREEN (-5602 2883);
FORCEPROP 2 LAST CDS_LIB mstr_standard
J 0
(-5600 2875);
PAINT MONO (-5600 2875);
DISPLAY INVISIBLE (-5600 2875);
FORCEPROP 1 LAST BODY_TYPE PLUMBING
J 0
(-5600 2825);
DISPLAY 1.595745 (-5600 2825);
PAINT GREEN (-5600 2825);
DISPLAY INVISIBLE (-5600 2825);
FORCEPROP 1 LAST HDL_TAP TRUE
J 0
(-5275 2750);
DISPLAY 1.595745 (-5275 2750);
PAINT GREEN (-5275 2750);
DISPLAY INVISIBLE (-5275 2750);
FORCEPROP 1 LAST PATH I49
J 0
(-5602 2875);
DISPLAY 0.872340 (-5602 2875);
PAINT GREEN (-5602 2875);
DISPLAY INVISIBLE (-5602 2875);
FORCEADD TAP..6
(-5600 625);
FORCEPROP 3 LASTPIN (-5550 625) SIG_NAME M_H_CLK_DN<0>
J 0
(-5540 635);
DISPLAY 0.659574 (-5540 635);
PAINT MONO (-5540 635);
DISPLAY INVISIBLE (-5540 635);
FORCEPROP 1 LASTPIN (-5550 625) BN 0
J 0
(-5602 633);
DISPLAY 0.617021 (-5602 633);
PAINT GREEN (-5602 633);
FORCEPROP 2 LAST CDS_LIB mstr_standard
J 0
(-5600 625);
PAINT MONO (-5600 625);
DISPLAY INVISIBLE (-5600 625);
FORCEPROP 1 LAST BODY_TYPE PLUMBING
J 0
(-5600 575);
DISPLAY 1.595745 (-5600 575);
PAINT GREEN (-5600 575);
DISPLAY INVISIBLE (-5600 575);
FORCEPROP 1 LAST HDL_TAP TRUE
J 0
(-5275 500);
DISPLAY 1.595745 (-5275 500);
PAINT GREEN (-5275 500);
DISPLAY INVISIBLE (-5275 500);
FORCEPROP 1 LAST PATH I5
J 0
(-5602 625);
DISPLAY 0.872340 (-5602 625);
PAINT GREEN (-5602 625);
DISPLAY INVISIBLE (-5602 625);
FORCEADD TAP..6
(-5600 2925);
FORCEPROP 3 LASTPIN (-5550 2925) SIG_NAME M_H_DQ<28>
J 0
(-5540 2935);
DISPLAY 0.659574 (-5540 2935);
PAINT MONO (-5540 2935);
DISPLAY INVISIBLE (-5540 2935);
FORCEPROP 1 LASTPIN (-5550 2925) BN 28
J 0
(-5602 2933);
DISPLAY 0.617021 (-5602 2933);
PAINT GREEN (-5602 2933);
FORCEPROP 2 LAST CDS_LIB mstr_standard
J 0
(-5600 2925);
PAINT MONO (-5600 2925);
DISPLAY INVISIBLE (-5600 2925);
FORCEPROP 1 LAST BODY_TYPE PLUMBING
J 0
(-5600 2875);
DISPLAY 1.595745 (-5600 2875);
PAINT GREEN (-5600 2875);
DISPLAY INVISIBLE (-5600 2875);
FORCEPROP 1 LAST HDL_TAP TRUE
J 0
(-5275 2800);
DISPLAY 1.595745 (-5275 2800);
PAINT GREEN (-5275 2800);
DISPLAY INVISIBLE (-5275 2800);
FORCEPROP 1 LAST PATH I50
J 0
(-5602 2925);
DISPLAY 0.872340 (-5602 2925);
PAINT GREEN (-5602 2925);
DISPLAY INVISIBLE (-5602 2925);
FORCEADD TAP..6
(-5600 2975);
FORCEPROP 3 LASTPIN (-5550 2975) SIG_NAME M_H_DQ<29>
J 0
(-5540 2985);
DISPLAY 0.659574 (-5540 2985);
PAINT MONO (-5540 2985);
DISPLAY INVISIBLE (-5540 2985);
FORCEPROP 1 LASTPIN (-5550 2975) BN 29
J 0
(-5602 2983);
DISPLAY 0.617021 (-5602 2983);
PAINT GREEN (-5602 2983);
FORCEPROP 2 LAST CDS_LIB mstr_standard
J 0
(-5600 2975);
PAINT MONO (-5600 2975);
DISPLAY INVISIBLE (-5600 2975);
FORCEPROP 1 LAST BODY_TYPE PLUMBING
J 0
(-5600 2925);
DISPLAY 1.595745 (-5600 2925);
PAINT GREEN (-5600 2925);
DISPLAY INVISIBLE (-5600 2925);
FORCEPROP 1 LAST HDL_TAP TRUE
J 0
(-5275 2850);
DISPLAY 1.595745 (-5275 2850);
PAINT GREEN (-5275 2850);
DISPLAY INVISIBLE (-5275 2850);
FORCEPROP 1 LAST PATH I51
J 0
(-5602 2975);
DISPLAY 0.872340 (-5602 2975);
PAINT GREEN (-5602 2975);
DISPLAY INVISIBLE (-5602 2975);
FORCEADD TAP..6
(-5600 3075);
FORCEPROP 3 LASTPIN (-5550 3075) SIG_NAME M_H_DQ<31>
J 0
(-5540 3085);
DISPLAY 0.659574 (-5540 3085);
PAINT MONO (-5540 3085);
DISPLAY INVISIBLE (-5540 3085);
FORCEPROP 1 LASTPIN (-5550 3075) BN 31
J 0
(-5602 3083);
DISPLAY 0.617021 (-5602 3083);
PAINT GREEN (-5602 3083);
FORCEPROP 2 LAST CDS_LIB mstr_standard
J 0
(-5600 3075);
PAINT MONO (-5600 3075);
DISPLAY INVISIBLE (-5600 3075);
FORCEPROP 1 LAST BODY_TYPE PLUMBING
J 0
(-5600 3025);
DISPLAY 1.595745 (-5600 3025);
PAINT GREEN (-5600 3025);
DISPLAY INVISIBLE (-5600 3025);
FORCEPROP 1 LAST HDL_TAP TRUE
J 0
(-5275 2950);
DISPLAY 1.595745 (-5275 2950);
PAINT GREEN (-5275 2950);
DISPLAY INVISIBLE (-5275 2950);
FORCEPROP 1 LAST PATH I52
J 0
(-5602 3075);
DISPLAY 0.872340 (-5602 3075);
PAINT GREEN (-5602 3075);
DISPLAY INVISIBLE (-5602 3075);
FORCEADD TAP..6
(-5600 3025);
FORCEPROP 3 LASTPIN (-5550 3025) SIG_NAME M_H_DQ<30>
J 0
(-5540 3035);
DISPLAY 0.659574 (-5540 3035);
PAINT MONO (-5540 3035);
DISPLAY INVISIBLE (-5540 3035);
FORCEPROP 1 LASTPIN (-5550 3025) BN 30
J 0
(-5602 3033);
DISPLAY 0.617021 (-5602 3033);
PAINT GREEN (-5602 3033);
FORCEPROP 2 LAST CDS_LIB mstr_standard
J 0
(-5600 3025);
PAINT MONO (-5600 3025);
DISPLAY INVISIBLE (-5600 3025);
FORCEPROP 1 LAST BODY_TYPE PLUMBING
J 0
(-5600 2975);
DISPLAY 1.595745 (-5600 2975);
PAINT GREEN (-5600 2975);
DISPLAY INVISIBLE (-5600 2975);
FORCEPROP 1 LAST HDL_TAP TRUE
J 0
(-5275 2900);
DISPLAY 1.595745 (-5275 2900);
PAINT GREEN (-5275 2900);
DISPLAY INVISIBLE (-5275 2900);
FORCEPROP 1 LAST PATH I53
J 0
(-5602 3025);
DISPLAY 0.872340 (-5602 3025);
PAINT GREEN (-5602 3025);
DISPLAY INVISIBLE (-5602 3025);
FORCEADD TAP..6
(-5600 3125);
FORCEPROP 3 LASTPIN (-5550 3125) SIG_NAME M_H_DQ<32>
J 0
(-5540 3135);
DISPLAY 0.659574 (-5540 3135);
PAINT MONO (-5540 3135);
DISPLAY INVISIBLE (-5540 3135);
FORCEPROP 1 LASTPIN (-5550 3125) BN 32
J 0
(-5602 3133);
DISPLAY 0.617021 (-5602 3133);
PAINT GREEN (-5602 3133);
FORCEPROP 2 LAST CDS_LIB mstr_standard
J 0
(-5600 3125);
PAINT MONO (-5600 3125);
DISPLAY INVISIBLE (-5600 3125);
FORCEPROP 1 LAST BODY_TYPE PLUMBING
J 0
(-5600 3075);
DISPLAY 1.595745 (-5600 3075);
PAINT GREEN (-5600 3075);
DISPLAY INVISIBLE (-5600 3075);
FORCEPROP 1 LAST HDL_TAP TRUE
J 0
(-5275 3000);
DISPLAY 1.595745 (-5275 3000);
PAINT GREEN (-5275 3000);
DISPLAY INVISIBLE (-5275 3000);
FORCEPROP 1 LAST PATH I54
J 0
(-5602 3125);
DISPLAY 0.872340 (-5602 3125);
PAINT GREEN (-5602 3125);
DISPLAY INVISIBLE (-5602 3125);
FORCEADD TAP..6
(-5600 3175);
FORCEPROP 3 LASTPIN (-5550 3175) SIG_NAME M_H_DQ<33>
J 0
(-5540 3185);
DISPLAY 0.659574 (-5540 3185);
PAINT MONO (-5540 3185);
DISPLAY INVISIBLE (-5540 3185);
FORCEPROP 1 LASTPIN (-5550 3175) BN 33
J 0
(-5602 3183);
DISPLAY 0.617021 (-5602 3183);
PAINT GREEN (-5602 3183);
FORCEPROP 2 LAST CDS_LIB mstr_standard
J 0
(-5600 3175);
PAINT MONO (-5600 3175);
DISPLAY INVISIBLE (-5600 3175);
FORCEPROP 1 LAST BODY_TYPE PLUMBING
J 0
(-5600 3125);
DISPLAY 1.595745 (-5600 3125);
PAINT GREEN (-5600 3125);
DISPLAY INVISIBLE (-5600 3125);
FORCEPROP 1 LAST HDL_TAP TRUE
J 0
(-5275 3050);
DISPLAY 1.595745 (-5275 3050);
PAINT GREEN (-5275 3050);
DISPLAY INVISIBLE (-5275 3050);
FORCEPROP 1 LAST PATH I55
J 0
(-5602 3175);
DISPLAY 0.872340 (-5602 3175);
PAINT GREEN (-5602 3175);
DISPLAY INVISIBLE (-5602 3175);
FORCEADD TAP..6
(-5600 3225);
FORCEPROP 3 LASTPIN (-5550 3225) SIG_NAME M_H_DQ<34>
J 0
(-5540 3235);
DISPLAY 0.659574 (-5540 3235);
PAINT MONO (-5540 3235);
DISPLAY INVISIBLE (-5540 3235);
FORCEPROP 1 LASTPIN (-5550 3225) BN 34
J 0
(-5602 3233);
DISPLAY 0.617021 (-5602 3233);
PAINT GREEN (-5602 3233);
FORCEPROP 2 LAST CDS_LIB mstr_standard
J 0
(-5600 3225);
PAINT MONO (-5600 3225);
DISPLAY INVISIBLE (-5600 3225);
FORCEPROP 1 LAST BODY_TYPE PLUMBING
J 0
(-5600 3175);
DISPLAY 1.595745 (-5600 3175);
PAINT GREEN (-5600 3175);
DISPLAY INVISIBLE (-5600 3175);
FORCEPROP 1 LAST HDL_TAP TRUE
J 0
(-5275 3100);
DISPLAY 1.595745 (-5275 3100);
PAINT GREEN (-5275 3100);
DISPLAY INVISIBLE (-5275 3100);
FORCEPROP 1 LAST PATH I56
J 0
(-5602 3225);
DISPLAY 0.872340 (-5602 3225);
PAINT GREEN (-5602 3225);
DISPLAY INVISIBLE (-5602 3225);
FORCEADD TAP..6
(-5600 3325);
FORCEPROP 3 LASTPIN (-5550 3325) SIG_NAME M_H_DQ<36>
J 0
(-5540 3335);
DISPLAY 0.659574 (-5540 3335);
PAINT MONO (-5540 3335);
DISPLAY INVISIBLE (-5540 3335);
FORCEPROP 1 LASTPIN (-5550 3325) BN 36
J 0
(-5602 3333);
DISPLAY 0.617021 (-5602 3333);
PAINT GREEN (-5602 3333);
FORCEPROP 2 LAST CDS_LIB mstr_standard
J 0
(-5600 3325);
PAINT MONO (-5600 3325);
DISPLAY INVISIBLE (-5600 3325);
FORCEPROP 1 LAST BODY_TYPE PLUMBING
J 0
(-5600 3275);
DISPLAY 1.595745 (-5600 3275);
PAINT GREEN (-5600 3275);
DISPLAY INVISIBLE (-5600 3275);
FORCEPROP 1 LAST HDL_TAP TRUE
J 0
(-5275 3200);
DISPLAY 1.595745 (-5275 3200);
PAINT GREEN (-5275 3200);
DISPLAY INVISIBLE (-5275 3200);
FORCEPROP 1 LAST PATH I57
J 0
(-5602 3325);
DISPLAY 0.872340 (-5602 3325);
PAINT GREEN (-5602 3325);
DISPLAY INVISIBLE (-5602 3325);
FORCEADD TAP..6
(-5600 3275);
FORCEPROP 3 LASTPIN (-5550 3275) SIG_NAME M_H_DQ<35>
J 0
(-5540 3285);
DISPLAY 0.659574 (-5540 3285);
PAINT MONO (-5540 3285);
DISPLAY INVISIBLE (-5540 3285);
FORCEPROP 1 LASTPIN (-5550 3275) BN 35
J 0
(-5602 3283);
DISPLAY 0.617021 (-5602 3283);
PAINT GREEN (-5602 3283);
FORCEPROP 2 LAST CDS_LIB mstr_standard
J 0
(-5600 3275);
PAINT MONO (-5600 3275);
DISPLAY INVISIBLE (-5600 3275);
FORCEPROP 1 LAST BODY_TYPE PLUMBING
J 0
(-5600 3225);
DISPLAY 1.595745 (-5600 3225);
PAINT GREEN (-5600 3225);
DISPLAY INVISIBLE (-5600 3225);
FORCEPROP 1 LAST HDL_TAP TRUE
J 0
(-5275 3150);
DISPLAY 1.595745 (-5275 3150);
PAINT GREEN (-5275 3150);
DISPLAY INVISIBLE (-5275 3150);
FORCEPROP 1 LAST PATH I58
J 0
(-5602 3275);
DISPLAY 0.872340 (-5602 3275);
PAINT GREEN (-5602 3275);
DISPLAY INVISIBLE (-5602 3275);
FORCEADD TAP..6
(-5600 3375);
FORCEPROP 3 LASTPIN (-5550 3375) SIG_NAME M_H_DQ<37>
J 0
(-5540 3385);
DISPLAY 0.659574 (-5540 3385);
PAINT MONO (-5540 3385);
DISPLAY INVISIBLE (-5540 3385);
FORCEPROP 1 LASTPIN (-5550 3375) BN 37
J 0
(-5602 3383);
DISPLAY 0.617021 (-5602 3383);
PAINT GREEN (-5602 3383);
FORCEPROP 2 LAST CDS_LIB mstr_standard
J 0
(-5600 3375);
PAINT MONO (-5600 3375);
DISPLAY INVISIBLE (-5600 3375);
FORCEPROP 1 LAST BODY_TYPE PLUMBING
J 0
(-5600 3325);
DISPLAY 1.595745 (-5600 3325);
PAINT GREEN (-5600 3325);
DISPLAY INVISIBLE (-5600 3325);
FORCEPROP 1 LAST HDL_TAP TRUE
J 0
(-5275 3250);
DISPLAY 1.595745 (-5275 3250);
PAINT GREEN (-5275 3250);
DISPLAY INVISIBLE (-5275 3250);
FORCEPROP 1 LAST PATH I59
J 0
(-5602 3375);
DISPLAY 0.872340 (-5602 3375);
PAINT GREEN (-5602 3375);
DISPLAY INVISIBLE (-5602 3375);
FORCEADD TAP..6
(-5600 675);
FORCEPROP 3 LASTPIN (-5550 675) SIG_NAME M_H_CLK_DN<1>
J 0
(-5540 685);
DISPLAY 0.659574 (-5540 685);
PAINT MONO (-5540 685);
DISPLAY INVISIBLE (-5540 685);
FORCEPROP 1 LASTPIN (-5550 675) BN 1
J 0
(-5602 683);
DISPLAY 0.617021 (-5602 683);
PAINT GREEN (-5602 683);
FORCEPROP 2 LAST CDS_LIB mstr_standard
J 0
(-5600 675);
PAINT MONO (-5600 675);
DISPLAY INVISIBLE (-5600 675);
FORCEPROP 1 LAST BODY_TYPE PLUMBING
J 0
(-5600 625);
DISPLAY 1.595745 (-5600 625);
PAINT GREEN (-5600 625);
DISPLAY INVISIBLE (-5600 625);
FORCEPROP 1 LAST HDL_TAP TRUE
J 0
(-5275 550);
DISPLAY 1.595745 (-5275 550);
PAINT GREEN (-5275 550);
DISPLAY INVISIBLE (-5275 550);
FORCEPROP 1 LAST PATH I6
J 0
(-5602 675);
DISPLAY 0.872340 (-5602 675);
PAINT GREEN (-5602 675);
DISPLAY INVISIBLE (-5602 675);
FORCEADD TAP..6
(-5600 3425);
FORCEPROP 3 LASTPIN (-5550 3425) SIG_NAME M_H_DQ<38>
J 0
(-5540 3435);
DISPLAY 0.659574 (-5540 3435);
PAINT MONO (-5540 3435);
DISPLAY INVISIBLE (-5540 3435);
FORCEPROP 1 LASTPIN (-5550 3425) BN 38
J 0
(-5602 3433);
DISPLAY 0.617021 (-5602 3433);
PAINT GREEN (-5602 3433);
FORCEPROP 2 LAST CDS_LIB mstr_standard
J 0
(-5600 3425);
PAINT MONO (-5600 3425);
DISPLAY INVISIBLE (-5600 3425);
FORCEPROP 1 LAST BODY_TYPE PLUMBING
J 0
(-5600 3375);
DISPLAY 1.595745 (-5600 3375);
PAINT GREEN (-5600 3375);
DISPLAY INVISIBLE (-5600 3375);
FORCEPROP 1 LAST HDL_TAP TRUE
J 0
(-5275 3300);
DISPLAY 1.595745 (-5275 3300);
PAINT GREEN (-5275 3300);
DISPLAY INVISIBLE (-5275 3300);
FORCEPROP 1 LAST PATH I60
J 0
(-5602 3425);
DISPLAY 0.872340 (-5602 3425);
PAINT GREEN (-5602 3425);
DISPLAY INVISIBLE (-5602 3425);
FORCEADD TAP..6
(-5600 3475);
FORCEPROP 3 LASTPIN (-5550 3475) SIG_NAME M_H_DQ<39>
J 0
(-5540 3485);
DISPLAY 0.659574 (-5540 3485);
PAINT MONO (-5540 3485);
DISPLAY INVISIBLE (-5540 3485);
FORCEPROP 1 LASTPIN (-5550 3475) BN 39
J 0
(-5602 3483);
DISPLAY 0.617021 (-5602 3483);
PAINT GREEN (-5602 3483);
FORCEPROP 2 LAST CDS_LIB mstr_standard
J 0
(-5600 3475);
PAINT MONO (-5600 3475);
DISPLAY INVISIBLE (-5600 3475);
FORCEPROP 1 LAST BODY_TYPE PLUMBING
J 0
(-5600 3425);
DISPLAY 1.595745 (-5600 3425);
PAINT GREEN (-5600 3425);
DISPLAY INVISIBLE (-5600 3425);
FORCEPROP 1 LAST HDL_TAP TRUE
J 0
(-5275 3350);
DISPLAY 1.595745 (-5275 3350);
PAINT GREEN (-5275 3350);
DISPLAY INVISIBLE (-5275 3350);
FORCEPROP 1 LAST PATH I61
J 0
(-5602 3475);
DISPLAY 0.872340 (-5602 3475);
PAINT GREEN (-5602 3475);
DISPLAY INVISIBLE (-5602 3475);
FORCEADD TAP..6
(-5600 3525);
FORCEPROP 3 LASTPIN (-5550 3525) SIG_NAME M_H_DQ<40>
J 0
(-5540 3535);
DISPLAY 0.659574 (-5540 3535);
PAINT MONO (-5540 3535);
DISPLAY INVISIBLE (-5540 3535);
FORCEPROP 1 LASTPIN (-5550 3525) BN 40
J 0
(-5602 3533);
DISPLAY 0.617021 (-5602 3533);
PAINT GREEN (-5602 3533);
FORCEPROP 2 LAST CDS_LIB mstr_standard
J 0
(-5600 3525);
PAINT MONO (-5600 3525);
DISPLAY INVISIBLE (-5600 3525);
FORCEPROP 1 LAST BODY_TYPE PLUMBING
J 0
(-5600 3475);
DISPLAY 1.595745 (-5600 3475);
PAINT GREEN (-5600 3475);
DISPLAY INVISIBLE (-5600 3475);
FORCEPROP 1 LAST HDL_TAP TRUE
J 0
(-5275 3400);
DISPLAY 1.595745 (-5275 3400);
PAINT GREEN (-5275 3400);
DISPLAY INVISIBLE (-5275 3400);
FORCEPROP 1 LAST PATH I62
J 0
(-5602 3525);
DISPLAY 0.872340 (-5602 3525);
PAINT GREEN (-5602 3525);
DISPLAY INVISIBLE (-5602 3525);
FORCEADD TAP..6
(-5600 3575);
FORCEPROP 3 LASTPIN (-5550 3575) SIG_NAME M_H_DQ<41>
J 0
(-5540 3585);
DISPLAY 0.659574 (-5540 3585);
PAINT MONO (-5540 3585);
DISPLAY INVISIBLE (-5540 3585);
FORCEPROP 1 LASTPIN (-5550 3575) BN 41
J 0
(-5602 3583);
DISPLAY 0.617021 (-5602 3583);
PAINT GREEN (-5602 3583);
FORCEPROP 2 LAST CDS_LIB mstr_standard
J 0
(-5600 3575);
PAINT MONO (-5600 3575);
DISPLAY INVISIBLE (-5600 3575);
FORCEPROP 1 LAST BODY_TYPE PLUMBING
J 0
(-5600 3525);
DISPLAY 1.595745 (-5600 3525);
PAINT GREEN (-5600 3525);
DISPLAY INVISIBLE (-5600 3525);
FORCEPROP 1 LAST HDL_TAP TRUE
J 0
(-5275 3450);
DISPLAY 1.595745 (-5275 3450);
PAINT GREEN (-5275 3450);
DISPLAY INVISIBLE (-5275 3450);
FORCEPROP 1 LAST PATH I63
J 0
(-5602 3575);
DISPLAY 0.872340 (-5602 3575);
PAINT GREEN (-5602 3575);
DISPLAY INVISIBLE (-5602 3575);
FORCEADD TAP..6
(-5600 3625);
FORCEPROP 3 LASTPIN (-5550 3625) SIG_NAME M_H_DQ<42>
J 0
(-5540 3635);
DISPLAY 0.659574 (-5540 3635);
PAINT MONO (-5540 3635);
DISPLAY INVISIBLE (-5540 3635);
FORCEPROP 1 LASTPIN (-5550 3625) BN 42
J 0
(-5602 3633);
DISPLAY 0.617021 (-5602 3633);
PAINT GREEN (-5602 3633);
FORCEPROP 2 LAST CDS_LIB mstr_standard
J 0
(-5600 3625);
PAINT MONO (-5600 3625);
DISPLAY INVISIBLE (-5600 3625);
FORCEPROP 1 LAST BODY_TYPE PLUMBING
J 0
(-5600 3575);
DISPLAY 1.595745 (-5600 3575);
PAINT GREEN (-5600 3575);
DISPLAY INVISIBLE (-5600 3575);
FORCEPROP 1 LAST HDL_TAP TRUE
J 0
(-5275 3500);
DISPLAY 1.595745 (-5275 3500);
PAINT GREEN (-5275 3500);
DISPLAY INVISIBLE (-5275 3500);
FORCEPROP 1 LAST PATH I64
J 0
(-5602 3625);
DISPLAY 0.872340 (-5602 3625);
PAINT GREEN (-5602 3625);
DISPLAY INVISIBLE (-5602 3625);
FORCEADD TAP..6
(-5600 3675);
FORCEPROP 3 LASTPIN (-5550 3675) SIG_NAME M_H_DQ<43>
J 0
(-5540 3685);
DISPLAY 0.659574 (-5540 3685);
PAINT MONO (-5540 3685);
DISPLAY INVISIBLE (-5540 3685);
FORCEPROP 1 LASTPIN (-5550 3675) BN 43
J 0
(-5602 3683);
DISPLAY 0.617021 (-5602 3683);
PAINT GREEN (-5602 3683);
FORCEPROP 2 LAST CDS_LIB mstr_standard
J 0
(-5600 3675);
PAINT MONO (-5600 3675);
DISPLAY INVISIBLE (-5600 3675);
FORCEPROP 1 LAST BODY_TYPE PLUMBING
J 0
(-5600 3625);
DISPLAY 1.595745 (-5600 3625);
PAINT GREEN (-5600 3625);
DISPLAY INVISIBLE (-5600 3625);
FORCEPROP 1 LAST HDL_TAP TRUE
J 0
(-5275 3550);
DISPLAY 1.595745 (-5275 3550);
PAINT GREEN (-5275 3550);
DISPLAY INVISIBLE (-5275 3550);
FORCEPROP 1 LAST PATH I65
J 0
(-5602 3675);
DISPLAY 0.872340 (-5602 3675);
PAINT GREEN (-5602 3675);
DISPLAY INVISIBLE (-5602 3675);
FORCEADD TAP..6
(-5600 3725);
FORCEPROP 3 LASTPIN (-5550 3725) SIG_NAME M_H_DQ<44>
J 0
(-5540 3735);
DISPLAY 0.659574 (-5540 3735);
PAINT MONO (-5540 3735);
DISPLAY INVISIBLE (-5540 3735);
FORCEPROP 1 LASTPIN (-5550 3725) BN 44
J 0
(-5602 3733);
DISPLAY 0.617021 (-5602 3733);
PAINT GREEN (-5602 3733);
FORCEPROP 2 LAST CDS_LIB mstr_standard
J 0
(-5600 3725);
PAINT MONO (-5600 3725);
DISPLAY INVISIBLE (-5600 3725);
FORCEPROP 1 LAST BODY_TYPE PLUMBING
J 0
(-5600 3675);
DISPLAY 1.595745 (-5600 3675);
PAINT GREEN (-5600 3675);
DISPLAY INVISIBLE (-5600 3675);
FORCEPROP 1 LAST HDL_TAP TRUE
J 0
(-5275 3600);
DISPLAY 1.595745 (-5275 3600);
PAINT GREEN (-5275 3600);
DISPLAY INVISIBLE (-5275 3600);
FORCEPROP 1 LAST PATH I66
J 0
(-5602 3725);
DISPLAY 0.872340 (-5602 3725);
PAINT GREEN (-5602 3725);
DISPLAY INVISIBLE (-5602 3725);
FORCEADD TAP..6
(-5600 3775);
FORCEPROP 3 LASTPIN (-5550 3775) SIG_NAME M_H_DQ<45>
J 0
(-5540 3785);
DISPLAY 0.659574 (-5540 3785);
PAINT MONO (-5540 3785);
DISPLAY INVISIBLE (-5540 3785);
FORCEPROP 1 LASTPIN (-5550 3775) BN 45
J 0
(-5602 3783);
DISPLAY 0.617021 (-5602 3783);
PAINT GREEN (-5602 3783);
FORCEPROP 2 LAST CDS_LIB mstr_standard
J 0
(-5600 3775);
PAINT MONO (-5600 3775);
DISPLAY INVISIBLE (-5600 3775);
FORCEPROP 1 LAST BODY_TYPE PLUMBING
J 0
(-5600 3725);
DISPLAY 1.595745 (-5600 3725);
PAINT GREEN (-5600 3725);
DISPLAY INVISIBLE (-5600 3725);
FORCEPROP 1 LAST HDL_TAP TRUE
J 0
(-5275 3650);
DISPLAY 1.595745 (-5275 3650);
PAINT GREEN (-5275 3650);
DISPLAY INVISIBLE (-5275 3650);
FORCEPROP 1 LAST PATH I67
J 0
(-5602 3775);
DISPLAY 0.872340 (-5602 3775);
PAINT GREEN (-5602 3775);
DISPLAY INVISIBLE (-5602 3775);
FORCEADD TAP..6
(-5600 3825);
FORCEPROP 3 LASTPIN (-5550 3825) SIG_NAME M_H_DQ<46>
J 0
(-5540 3835);
DISPLAY 0.659574 (-5540 3835);
PAINT MONO (-5540 3835);
DISPLAY INVISIBLE (-5540 3835);
FORCEPROP 1 LASTPIN (-5550 3825) BN 46
J 0
(-5602 3833);
DISPLAY 0.617021 (-5602 3833);
PAINT GREEN (-5602 3833);
FORCEPROP 2 LAST CDS_LIB mstr_standard
J 0
(-5600 3825);
PAINT MONO (-5600 3825);
DISPLAY INVISIBLE (-5600 3825);
FORCEPROP 1 LAST BODY_TYPE PLUMBING
J 0
(-5600 3775);
DISPLAY 1.595745 (-5600 3775);
PAINT GREEN (-5600 3775);
DISPLAY INVISIBLE (-5600 3775);
FORCEPROP 1 LAST HDL_TAP TRUE
J 0
(-5275 3700);
DISPLAY 1.595745 (-5275 3700);
PAINT GREEN (-5275 3700);
DISPLAY INVISIBLE (-5275 3700);
FORCEPROP 1 LAST PATH I68
J 0
(-5602 3825);
DISPLAY 0.872340 (-5602 3825);
PAINT GREEN (-5602 3825);
DISPLAY INVISIBLE (-5602 3825);
FORCEADD TAP..6
(-5600 3875);
FORCEPROP 3 LASTPIN (-5550 3875) SIG_NAME M_H_DQ<47>
J 0
(-5540 3885);
DISPLAY 0.659574 (-5540 3885);
PAINT MONO (-5540 3885);
DISPLAY INVISIBLE (-5540 3885);
FORCEPROP 1 LASTPIN (-5550 3875) BN 47
J 0
(-5602 3883);
DISPLAY 0.617021 (-5602 3883);
PAINT GREEN (-5602 3883);
FORCEPROP 2 LAST CDS_LIB mstr_standard
J 0
(-5600 3875);
PAINT MONO (-5600 3875);
DISPLAY INVISIBLE (-5600 3875);
FORCEPROP 1 LAST BODY_TYPE PLUMBING
J 0
(-5600 3825);
DISPLAY 1.595745 (-5600 3825);
PAINT GREEN (-5600 3825);
DISPLAY INVISIBLE (-5600 3825);
FORCEPROP 1 LAST HDL_TAP TRUE
J 0
(-5275 3750);
DISPLAY 1.595745 (-5275 3750);
PAINT GREEN (-5275 3750);
DISPLAY INVISIBLE (-5275 3750);
FORCEPROP 1 LAST PATH I69
J 0
(-5602 3875);
DISPLAY 0.872340 (-5602 3875);
PAINT GREEN (-5602 3875);
DISPLAY INVISIBLE (-5602 3875);
FORCEADD TAP..6
(-5600 775);
FORCEPROP 3 LASTPIN (-5550 775) SIG_NAME M_H_CLK_DN<3>
J 0
(-5540 785);
DISPLAY 0.659574 (-5540 785);
PAINT MONO (-5540 785);
DISPLAY INVISIBLE (-5540 785);
FORCEPROP 1 LASTPIN (-5550 775) BN 3
J 0
(-5602 783);
DISPLAY 0.617021 (-5602 783);
PAINT GREEN (-5602 783);
FORCEPROP 2 LAST CDS_LIB mstr_standard
J 0
(-5600 775);
PAINT MONO (-5600 775);
DISPLAY INVISIBLE (-5600 775);
FORCEPROP 1 LAST BODY_TYPE PLUMBING
J 0
(-5600 725);
DISPLAY 1.595745 (-5600 725);
PAINT GREEN (-5600 725);
DISPLAY INVISIBLE (-5600 725);
FORCEPROP 1 LAST HDL_TAP TRUE
J 0
(-5275 650);
DISPLAY 1.595745 (-5275 650);
PAINT GREEN (-5275 650);
DISPLAY INVISIBLE (-5275 650);
FORCEPROP 1 LAST PATH I7
J 0
(-5602 775);
DISPLAY 0.872340 (-5602 775);
PAINT GREEN (-5602 775);
DISPLAY INVISIBLE (-5602 775);
FORCEADD TAP..6
(-5600 3925);
FORCEPROP 3 LASTPIN (-5550 3925) SIG_NAME M_H_DQ<48>
J 0
(-5540 3935);
DISPLAY 0.659574 (-5540 3935);
PAINT MONO (-5540 3935);
DISPLAY INVISIBLE (-5540 3935);
FORCEPROP 1 LASTPIN (-5550 3925) BN 48
J 0
(-5602 3933);
DISPLAY 0.617021 (-5602 3933);
PAINT GREEN (-5602 3933);
FORCEPROP 2 LAST CDS_LIB mstr_standard
J 0
(-5600 3925);
PAINT MONO (-5600 3925);
DISPLAY INVISIBLE (-5600 3925);
FORCEPROP 1 LAST BODY_TYPE PLUMBING
J 0
(-5600 3875);
DISPLAY 1.595745 (-5600 3875);
PAINT GREEN (-5600 3875);
DISPLAY INVISIBLE (-5600 3875);
FORCEPROP 1 LAST HDL_TAP TRUE
J 0
(-5275 3800);
DISPLAY 1.595745 (-5275 3800);
PAINT GREEN (-5275 3800);
DISPLAY INVISIBLE (-5275 3800);
FORCEPROP 1 LAST PATH I70
J 0
(-5602 3925);
DISPLAY 0.872340 (-5602 3925);
PAINT GREEN (-5602 3925);
DISPLAY INVISIBLE (-5602 3925);
FORCEADD TAP..6
(-5600 3975);
FORCEPROP 3 LASTPIN (-5550 3975) SIG_NAME M_H_DQ<49>
J 0
(-5540 3985);
DISPLAY 0.659574 (-5540 3985);
PAINT MONO (-5540 3985);
DISPLAY INVISIBLE (-5540 3985);
FORCEPROP 1 LASTPIN (-5550 3975) BN 49
J 0
(-5602 3983);
DISPLAY 0.617021 (-5602 3983);
PAINT GREEN (-5602 3983);
FORCEPROP 2 LAST CDS_LIB mstr_standard
J 0
(-5600 3975);
PAINT MONO (-5600 3975);
DISPLAY INVISIBLE (-5600 3975);
FORCEPROP 1 LAST BODY_TYPE PLUMBING
J 0
(-5600 3925);
DISPLAY 1.595745 (-5600 3925);
PAINT GREEN (-5600 3925);
DISPLAY INVISIBLE (-5600 3925);
FORCEPROP 1 LAST HDL_TAP TRUE
J 0
(-5275 3850);
DISPLAY 1.595745 (-5275 3850);
PAINT GREEN (-5275 3850);
DISPLAY INVISIBLE (-5275 3850);
FORCEPROP 1 LAST PATH I71
J 0
(-5602 3975);
DISPLAY 0.872340 (-5602 3975);
PAINT GREEN (-5602 3975);
DISPLAY INVISIBLE (-5602 3975);
FORCEADD OFFPAGE..6
(-6450 4800);
FORCEPROP 2 LAST $XR1 80 
J 0
(-6789 4800);
DISPLAY 0.638298 (-6789 4800);
PAINT MONO (-6789 4800);
FORCEPROP 2 LAST $XR0 79 
J 0
(-6699 4800);
DISPLAY 0.638298 (-6699 4800);
PAINT MONO (-6699 4800);
FORCEPROP 2 LAST CDS_LIB mstr_standard
J 0
(-6450 4800);
PAINT MONO (-6450 4800);
DISPLAY INVISIBLE (-6450 4800);
FORCEPROP 1 LAST OFFPAGE TRUE
J 0
(-6125 4675);
DISPLAY 1.170213 (-6125 4675);
PAINT GREEN (-6125 4675);
DISPLAY INVISIBLE (-6125 4675);
FORCEPROP 1 LAST COMMENT_BODY TRUE
J 0
(-6350 4725);
DISPLAY 1.170213 (-6350 4725);
PAINT GREEN (-6350 4725);
DISPLAY INVISIBLE (-6350 4725);
FORCEPROP 2 LAST PATH I72
J 0
(-6400 4875);
DISPLAY 1.021277 (-6400 4875);
PAINT ORANGE (-6400 4875);
DISPLAY INVISIBLE (-6400 4875);
FORCEADD TAP..6
(-5600 4025);
FORCEPROP 3 LASTPIN (-5550 4025) SIG_NAME M_H_DQ<50>
J 0
(-5540 4035);
DISPLAY 0.659574 (-5540 4035);
PAINT MONO (-5540 4035);
DISPLAY INVISIBLE (-5540 4035);
FORCEPROP 1 LASTPIN (-5550 4025) BN 50
J 0
(-5602 4033);
DISPLAY 0.617021 (-5602 4033);
PAINT GREEN (-5602 4033);
FORCEPROP 2 LAST CDS_LIB mstr_standard
J 0
(-5600 4025);
PAINT MONO (-5600 4025);
DISPLAY INVISIBLE (-5600 4025);
FORCEPROP 1 LAST BODY_TYPE PLUMBING
J 0
(-5600 3975);
DISPLAY 1.595745 (-5600 3975);
PAINT GREEN (-5600 3975);
DISPLAY INVISIBLE (-5600 3975);
FORCEPROP 1 LAST HDL_TAP TRUE
J 0
(-5275 3900);
DISPLAY 1.595745 (-5275 3900);
PAINT GREEN (-5275 3900);
DISPLAY INVISIBLE (-5275 3900);
FORCEPROP 1 LAST PATH I73
J 0
(-5602 4025);
DISPLAY 0.872340 (-5602 4025);
PAINT GREEN (-5602 4025);
DISPLAY INVISIBLE (-5602 4025);
FORCEADD TAP..6
(-5600 4075);
FORCEPROP 3 LASTPIN (-5550 4075) SIG_NAME M_H_DQ<51>
J 0
(-5540 4085);
DISPLAY 0.659574 (-5540 4085);
PAINT MONO (-5540 4085);
DISPLAY INVISIBLE (-5540 4085);
FORCEPROP 1 LASTPIN (-5550 4075) BN 51
J 0
(-5602 4083);
DISPLAY 0.617021 (-5602 4083);
PAINT GREEN (-5602 4083);
FORCEPROP 2 LAST CDS_LIB mstr_standard
J 0
(-5600 4075);
PAINT MONO (-5600 4075);
DISPLAY INVISIBLE (-5600 4075);
FORCEPROP 1 LAST BODY_TYPE PLUMBING
J 0
(-5600 4025);
DISPLAY 1.595745 (-5600 4025);
PAINT GREEN (-5600 4025);
DISPLAY INVISIBLE (-5600 4025);
FORCEPROP 1 LAST HDL_TAP TRUE
J 0
(-5275 3950);
DISPLAY 1.595745 (-5275 3950);
PAINT GREEN (-5275 3950);
DISPLAY INVISIBLE (-5275 3950);
FORCEPROP 1 LAST PATH I74
J 0
(-5602 4075);
DISPLAY 0.872340 (-5602 4075);
PAINT GREEN (-5602 4075);
DISPLAY INVISIBLE (-5602 4075);
FORCEADD TAP..6
(-5600 4125);
FORCEPROP 3 LASTPIN (-5550 4125) SIG_NAME M_H_DQ<52>
J 0
(-5540 4135);
DISPLAY 0.659574 (-5540 4135);
PAINT MONO (-5540 4135);
DISPLAY INVISIBLE (-5540 4135);
FORCEPROP 1 LASTPIN (-5550 4125) BN 52
J 0
(-5602 4133);
DISPLAY 0.617021 (-5602 4133);
PAINT GREEN (-5602 4133);
FORCEPROP 2 LAST CDS_LIB mstr_standard
J 0
(-5600 4125);
PAINT MONO (-5600 4125);
DISPLAY INVISIBLE (-5600 4125);
FORCEPROP 1 LAST BODY_TYPE PLUMBING
J 0
(-5600 4075);
DISPLAY 1.595745 (-5600 4075);
PAINT GREEN (-5600 4075);
DISPLAY INVISIBLE (-5600 4075);
FORCEPROP 1 LAST HDL_TAP TRUE
J 0
(-5275 4000);
DISPLAY 1.595745 (-5275 4000);
PAINT GREEN (-5275 4000);
DISPLAY INVISIBLE (-5275 4000);
FORCEPROP 1 LAST PATH I75
J 0
(-5602 4125);
DISPLAY 0.872340 (-5602 4125);
PAINT GREEN (-5602 4125);
DISPLAY INVISIBLE (-5602 4125);
FORCEADD TAP..6
(-5600 4175);
FORCEPROP 3 LASTPIN (-5550 4175) SIG_NAME M_H_DQ<53>
J 0
(-5540 4185);
DISPLAY 0.659574 (-5540 4185);
PAINT MONO (-5540 4185);
DISPLAY INVISIBLE (-5540 4185);
FORCEPROP 1 LASTPIN (-5550 4175) BN 53
J 0
(-5602 4183);
DISPLAY 0.617021 (-5602 4183);
PAINT GREEN (-5602 4183);
FORCEPROP 2 LAST CDS_LIB mstr_standard
J 0
(-5600 4175);
PAINT MONO (-5600 4175);
DISPLAY INVISIBLE (-5600 4175);
FORCEPROP 1 LAST BODY_TYPE PLUMBING
J 0
(-5600 4125);
DISPLAY 1.595745 (-5600 4125);
PAINT GREEN (-5600 4125);
DISPLAY INVISIBLE (-5600 4125);
FORCEPROP 1 LAST HDL_TAP TRUE
J 0
(-5275 4050);
DISPLAY 1.595745 (-5275 4050);
PAINT GREEN (-5275 4050);
DISPLAY INVISIBLE (-5275 4050);
FORCEPROP 1 LAST PATH I76
J 0
(-5602 4175);
DISPLAY 0.872340 (-5602 4175);
PAINT GREEN (-5602 4175);
DISPLAY INVISIBLE (-5602 4175);
FORCEADD TAP..6
(-5600 4225);
FORCEPROP 3 LASTPIN (-5550 4225) SIG_NAME M_H_DQ<54>
J 0
(-5540 4235);
DISPLAY 0.659574 (-5540 4235);
PAINT MONO (-5540 4235);
DISPLAY INVISIBLE (-5540 4235);
FORCEPROP 1 LASTPIN (-5550 4225) BN 54
J 0
(-5602 4233);
DISPLAY 0.617021 (-5602 4233);
PAINT GREEN (-5602 4233);
FORCEPROP 2 LAST CDS_LIB mstr_standard
J 0
(-5600 4225);
PAINT MONO (-5600 4225);
DISPLAY INVISIBLE (-5600 4225);
FORCEPROP 1 LAST BODY_TYPE PLUMBING
J 0
(-5600 4175);
DISPLAY 1.595745 (-5600 4175);
PAINT GREEN (-5600 4175);
DISPLAY INVISIBLE (-5600 4175);
FORCEPROP 1 LAST HDL_TAP TRUE
J 0
(-5275 4100);
DISPLAY 1.595745 (-5275 4100);
PAINT GREEN (-5275 4100);
DISPLAY INVISIBLE (-5275 4100);
FORCEPROP 1 LAST PATH I77
J 0
(-5602 4225);
DISPLAY 0.872340 (-5602 4225);
PAINT GREEN (-5602 4225);
DISPLAY INVISIBLE (-5602 4225);
FORCEADD TAP..6
(-5600 4275);
FORCEPROP 3 LASTPIN (-5550 4275) SIG_NAME M_H_DQ<55>
J 0
(-5540 4285);
DISPLAY 0.659574 (-5540 4285);
PAINT MONO (-5540 4285);
DISPLAY INVISIBLE (-5540 4285);
FORCEPROP 1 LASTPIN (-5550 4275) BN 55
J 0
(-5602 4283);
DISPLAY 0.617021 (-5602 4283);
PAINT GREEN (-5602 4283);
FORCEPROP 2 LAST CDS_LIB mstr_standard
J 0
(-5600 4275);
PAINT MONO (-5600 4275);
DISPLAY INVISIBLE (-5600 4275);
FORCEPROP 1 LAST BODY_TYPE PLUMBING
J 0
(-5600 4225);
DISPLAY 1.595745 (-5600 4225);
PAINT GREEN (-5600 4225);
DISPLAY INVISIBLE (-5600 4225);
FORCEPROP 1 LAST HDL_TAP TRUE
J 0
(-5275 4150);
DISPLAY 1.595745 (-5275 4150);
PAINT GREEN (-5275 4150);
DISPLAY INVISIBLE (-5275 4150);
FORCEPROP 1 LAST PATH I78
J 0
(-5602 4275);
DISPLAY 0.872340 (-5602 4275);
PAINT GREEN (-5602 4275);
DISPLAY INVISIBLE (-5602 4275);
FORCEADD TAP..6
(-5600 4325);
FORCEPROP 3 LASTPIN (-5550 4325) SIG_NAME M_H_DQ<56>
J 0
(-5540 4335);
DISPLAY 0.659574 (-5540 4335);
PAINT MONO (-5540 4335);
DISPLAY INVISIBLE (-5540 4335);
FORCEPROP 1 LASTPIN (-5550 4325) BN 56
J 0
(-5602 4333);
DISPLAY 0.617021 (-5602 4333);
PAINT GREEN (-5602 4333);
FORCEPROP 2 LAST CDS_LIB mstr_standard
J 0
(-5600 4325);
PAINT MONO (-5600 4325);
DISPLAY INVISIBLE (-5600 4325);
FORCEPROP 1 LAST BODY_TYPE PLUMBING
J 0
(-5600 4275);
DISPLAY 1.595745 (-5600 4275);
PAINT GREEN (-5600 4275);
DISPLAY INVISIBLE (-5600 4275);
FORCEPROP 1 LAST HDL_TAP TRUE
J 0
(-5275 4200);
DISPLAY 1.595745 (-5275 4200);
PAINT GREEN (-5275 4200);
DISPLAY INVISIBLE (-5275 4200);
FORCEPROP 1 LAST PATH I79
J 0
(-5602 4325);
DISPLAY 0.872340 (-5602 4325);
PAINT GREEN (-5602 4325);
DISPLAY INVISIBLE (-5602 4325);
FORCEADD TAP..6
(-5600 725);
FORCEPROP 3 LASTPIN (-5550 725) SIG_NAME M_H_CLK_DN<2>
J 0
(-5540 735);
DISPLAY 0.659574 (-5540 735);
PAINT MONO (-5540 735);
DISPLAY INVISIBLE (-5540 735);
FORCEPROP 1 LASTPIN (-5550 725) BN 2
J 0
(-5602 733);
DISPLAY 0.617021 (-5602 733);
PAINT GREEN (-5602 733);
FORCEPROP 2 LAST CDS_LIB mstr_standard
J 0
(-5600 725);
PAINT MONO (-5600 725);
DISPLAY INVISIBLE (-5600 725);
FORCEPROP 1 LAST BODY_TYPE PLUMBING
J 0
(-5600 675);
DISPLAY 1.595745 (-5600 675);
PAINT GREEN (-5600 675);
DISPLAY INVISIBLE (-5600 675);
FORCEPROP 1 LAST HDL_TAP TRUE
J 0
(-5275 600);
DISPLAY 1.595745 (-5275 600);
PAINT GREEN (-5275 600);
DISPLAY INVISIBLE (-5275 600);
FORCEPROP 1 LAST PATH I8
J 0
(-5602 725);
DISPLAY 0.872340 (-5602 725);
PAINT GREEN (-5602 725);
DISPLAY INVISIBLE (-5602 725);
FORCEADD TAP..6
(-5600 4375);
FORCEPROP 3 LASTPIN (-5550 4375) SIG_NAME M_H_DQ<57>
J 0
(-5540 4385);
DISPLAY 0.659574 (-5540 4385);
PAINT MONO (-5540 4385);
DISPLAY INVISIBLE (-5540 4385);
FORCEPROP 1 LASTPIN (-5550 4375) BN 57
J 0
(-5602 4383);
DISPLAY 0.617021 (-5602 4383);
PAINT GREEN (-5602 4383);
FORCEPROP 2 LAST CDS_LIB mstr_standard
J 0
(-5600 4375);
PAINT MONO (-5600 4375);
DISPLAY INVISIBLE (-5600 4375);
FORCEPROP 1 LAST BODY_TYPE PLUMBING
J 0
(-5600 4325);
DISPLAY 1.595745 (-5600 4325);
PAINT GREEN (-5600 4325);
DISPLAY INVISIBLE (-5600 4325);
FORCEPROP 1 LAST HDL_TAP TRUE
J 0
(-5275 4250);
DISPLAY 1.595745 (-5275 4250);
PAINT GREEN (-5275 4250);
DISPLAY INVISIBLE (-5275 4250);
FORCEPROP 1 LAST PATH I80
J 0
(-5602 4375);
DISPLAY 0.872340 (-5602 4375);
PAINT GREEN (-5602 4375);
DISPLAY INVISIBLE (-5602 4375);
FORCEADD TAP..6
(-5600 4425);
FORCEPROP 3 LASTPIN (-5550 4425) SIG_NAME M_H_DQ<58>
J 0
(-5540 4435);
DISPLAY 0.659574 (-5540 4435);
PAINT MONO (-5540 4435);
DISPLAY INVISIBLE (-5540 4435);
FORCEPROP 1 LASTPIN (-5550 4425) BN 58
J 0
(-5602 4433);
DISPLAY 0.617021 (-5602 4433);
PAINT GREEN (-5602 4433);
FORCEPROP 2 LAST CDS_LIB mstr_standard
J 0
(-5600 4425);
PAINT MONO (-5600 4425);
DISPLAY INVISIBLE (-5600 4425);
FORCEPROP 1 LAST BODY_TYPE PLUMBING
J 0
(-5600 4375);
DISPLAY 1.595745 (-5600 4375);
PAINT GREEN (-5600 4375);
DISPLAY INVISIBLE (-5600 4375);
FORCEPROP 1 LAST HDL_TAP TRUE
J 0
(-5275 4300);
DISPLAY 1.595745 (-5275 4300);
PAINT GREEN (-5275 4300);
DISPLAY INVISIBLE (-5275 4300);
FORCEPROP 1 LAST PATH I81
J 0
(-5602 4425);
DISPLAY 0.872340 (-5602 4425);
PAINT GREEN (-5602 4425);
DISPLAY INVISIBLE (-5602 4425);
FORCEADD TAP..6
(-5600 4475);
FORCEPROP 3 LASTPIN (-5550 4475) SIG_NAME M_H_DQ<59>
J 0
(-5540 4485);
DISPLAY 0.659574 (-5540 4485);
PAINT MONO (-5540 4485);
DISPLAY INVISIBLE (-5540 4485);
FORCEPROP 1 LASTPIN (-5550 4475) BN 59
J 0
(-5602 4483);
DISPLAY 0.617021 (-5602 4483);
PAINT GREEN (-5602 4483);
FORCEPROP 2 LAST CDS_LIB mstr_standard
J 0
(-5600 4475);
PAINT MONO (-5600 4475);
DISPLAY INVISIBLE (-5600 4475);
FORCEPROP 1 LAST BODY_TYPE PLUMBING
J 0
(-5600 4425);
DISPLAY 1.595745 (-5600 4425);
PAINT GREEN (-5600 4425);
DISPLAY INVISIBLE (-5600 4425);
FORCEPROP 1 LAST HDL_TAP TRUE
J 0
(-5275 4350);
DISPLAY 1.595745 (-5275 4350);
PAINT GREEN (-5275 4350);
DISPLAY INVISIBLE (-5275 4350);
FORCEPROP 1 LAST PATH I82
J 0
(-5602 4475);
DISPLAY 0.872340 (-5602 4475);
PAINT GREEN (-5602 4475);
DISPLAY INVISIBLE (-5602 4475);
FORCEADD TAP..6
(-5600 4525);
FORCEPROP 3 LASTPIN (-5550 4525) SIG_NAME M_H_DQ<60>
J 0
(-5540 4535);
DISPLAY 0.659574 (-5540 4535);
PAINT MONO (-5540 4535);
DISPLAY INVISIBLE (-5540 4535);
FORCEPROP 1 LASTPIN (-5550 4525) BN 60
J 0
(-5602 4533);
DISPLAY 0.617021 (-5602 4533);
PAINT GREEN (-5602 4533);
FORCEPROP 2 LAST CDS_LIB mstr_standard
J 0
(-5600 4525);
PAINT MONO (-5600 4525);
DISPLAY INVISIBLE (-5600 4525);
FORCEPROP 1 LAST BODY_TYPE PLUMBING
J 0
(-5600 4475);
DISPLAY 1.595745 (-5600 4475);
PAINT GREEN (-5600 4475);
DISPLAY INVISIBLE (-5600 4475);
FORCEPROP 1 LAST HDL_TAP TRUE
J 0
(-5275 4400);
DISPLAY 1.595745 (-5275 4400);
PAINT GREEN (-5275 4400);
DISPLAY INVISIBLE (-5275 4400);
FORCEPROP 1 LAST PATH I83
J 0
(-5602 4525);
DISPLAY 0.872340 (-5602 4525);
PAINT GREEN (-5602 4525);
DISPLAY INVISIBLE (-5602 4525);
FORCEADD TAP..6
(-5600 4575);
FORCEPROP 3 LASTPIN (-5550 4575) SIG_NAME M_H_DQ<61>
J 0
(-5540 4585);
DISPLAY 0.659574 (-5540 4585);
PAINT MONO (-5540 4585);
DISPLAY INVISIBLE (-5540 4585);
FORCEPROP 1 LASTPIN (-5550 4575) BN 61
J 0
(-5602 4583);
DISPLAY 0.617021 (-5602 4583);
PAINT GREEN (-5602 4583);
FORCEPROP 2 LAST CDS_LIB mstr_standard
J 0
(-5600 4575);
PAINT MONO (-5600 4575);
DISPLAY INVISIBLE (-5600 4575);
FORCEPROP 1 LAST BODY_TYPE PLUMBING
J 0
(-5600 4525);
DISPLAY 1.595745 (-5600 4525);
PAINT GREEN (-5600 4525);
DISPLAY INVISIBLE (-5600 4525);
FORCEPROP 1 LAST HDL_TAP TRUE
J 0
(-5275 4450);
DISPLAY 1.595745 (-5275 4450);
PAINT GREEN (-5275 4450);
DISPLAY INVISIBLE (-5275 4450);
FORCEPROP 1 LAST PATH I84
J 0
(-5602 4575);
DISPLAY 0.872340 (-5602 4575);
PAINT GREEN (-5602 4575);
DISPLAY INVISIBLE (-5602 4575);
FORCEADD TAP..6
(-5600 4625);
FORCEPROP 3 LASTPIN (-5550 4625) SIG_NAME M_H_DQ<62>
J 0
(-5540 4635);
DISPLAY 0.659574 (-5540 4635);
PAINT MONO (-5540 4635);
DISPLAY INVISIBLE (-5540 4635);
FORCEPROP 1 LASTPIN (-5550 4625) BN 62
J 0
(-5602 4633);
DISPLAY 0.617021 (-5602 4633);
PAINT GREEN (-5602 4633);
FORCEPROP 2 LAST CDS_LIB mstr_standard
J 0
(-5600 4625);
PAINT MONO (-5600 4625);
DISPLAY INVISIBLE (-5600 4625);
FORCEPROP 1 LAST BODY_TYPE PLUMBING
J 0
(-5600 4575);
DISPLAY 1.595745 (-5600 4575);
PAINT GREEN (-5600 4575);
DISPLAY INVISIBLE (-5600 4575);
FORCEPROP 1 LAST HDL_TAP TRUE
J 0
(-5275 4500);
DISPLAY 1.595745 (-5275 4500);
PAINT GREEN (-5275 4500);
DISPLAY INVISIBLE (-5275 4500);
FORCEPROP 1 LAST PATH I85
J 0
(-5602 4625);
DISPLAY 0.872340 (-5602 4625);
PAINT GREEN (-5602 4625);
DISPLAY INVISIBLE (-5602 4625);
FORCEADD TAP..6
(-5600 4675);
FORCEPROP 3 LASTPIN (-5550 4675) SIG_NAME M_H_DQ<63>
J 0
(-5540 4685);
DISPLAY 0.659574 (-5540 4685);
PAINT MONO (-5540 4685);
DISPLAY INVISIBLE (-5540 4685);
FORCEPROP 1 LASTPIN (-5550 4675) BN 63
J 0
(-5602 4683);
DISPLAY 0.617021 (-5602 4683);
PAINT GREEN (-5602 4683);
FORCEPROP 2 LAST CDS_LIB mstr_standard
J 0
(-5600 4675);
PAINT MONO (-5600 4675);
DISPLAY INVISIBLE (-5600 4675);
FORCEPROP 1 LAST BODY_TYPE PLUMBING
J 0
(-5600 4625);
DISPLAY 1.595745 (-5600 4625);
PAINT GREEN (-5600 4625);
DISPLAY INVISIBLE (-5600 4625);
FORCEPROP 1 LAST HDL_TAP TRUE
J 0
(-5275 4550);
DISPLAY 1.595745 (-5275 4550);
PAINT GREEN (-5275 4550);
DISPLAY INVISIBLE (-5275 4550);
FORCEPROP 1 LAST PATH I86
J 0
(-5602 4675);
DISPLAY 0.872340 (-5602 4675);
PAINT GREEN (-5602 4675);
DISPLAY INVISIBLE (-5602 4675);
FORCEADD TAP..6
R 2
(-2875 775);
FORCEPROP 3 LASTPIN (-2925 775) SIG_NAME M_H_BA<1>
J 0
(-2915 785);
DISPLAY 0.659574 (-2915 785);
PAINT MONO (-2915 785);
DISPLAY INVISIBLE (-2915 785);
FORCEPROP 1 LASTPIN (-2925 775) BN 1
J 2
(-2873 783);
DISPLAY 0.617021 (-2873 783);
PAINT GREEN (-2873 783);
FORCEPROP 2 LAST CDS_LIB mstr_standard
J 0
(-2875 775);
PAINT MONO (-2875 775);
DISPLAY INVISIBLE (-2875 775);
FORCEPROP 1 LAST BODY_TYPE PLUMBING
J 2
(-2875 725);
DISPLAY 1.595745 (-2875 725);
PAINT GREEN (-2875 725);
DISPLAY INVISIBLE (-2875 725);
FORCEPROP 1 LAST HDL_TAP TRUE
J 2
(-3200 650);
DISPLAY 1.595745 (-3200 650);
PAINT GREEN (-3200 650);
DISPLAY INVISIBLE (-3200 650);
FORCEPROP 1 LAST PATH I87
J 2
(-2873 775);
DISPLAY 0.872340 (-2873 775);
PAINT GREEN (-2873 775);
DISPLAY INVISIBLE (-2873 775);
FORCEADD TAP..6
R 2
(-2875 725);
FORCEPROP 3 LASTPIN (-2925 725) SIG_NAME M_H_BA<0>
J 0
(-2915 735);
DISPLAY 0.659574 (-2915 735);
PAINT MONO (-2915 735);
DISPLAY INVISIBLE (-2915 735);
FORCEPROP 1 LASTPIN (-2925 725) BN 0
J 2
(-2873 733);
DISPLAY 0.617021 (-2873 733);
PAINT GREEN (-2873 733);
FORCEPROP 2 LAST CDS_LIB mstr_standard
J 0
(-2875 725);
PAINT MONO (-2875 725);
DISPLAY INVISIBLE (-2875 725);
FORCEPROP 1 LAST BODY_TYPE PLUMBING
J 2
(-2875 675);
DISPLAY 1.595745 (-2875 675);
PAINT GREEN (-2875 675);
DISPLAY INVISIBLE (-2875 675);
FORCEPROP 1 LAST HDL_TAP TRUE
J 2
(-3200 600);
DISPLAY 1.595745 (-3200 600);
PAINT GREEN (-3200 600);
DISPLAY INVISIBLE (-3200 600);
FORCEPROP 1 LAST PATH I88
J 2
(-2873 725);
DISPLAY 0.872340 (-2873 725);
PAINT GREEN (-2873 725);
DISPLAY INVISIBLE (-2873 725);
FORCEADD TAP..6
R 2
(-2875 825);
FORCEPROP 3 LASTPIN (-2925 825) SIG_NAME M_H_BG<0>
J 0
(-2915 835);
DISPLAY 0.659574 (-2915 835);
PAINT MONO (-2915 835);
DISPLAY INVISIBLE (-2915 835);
FORCEPROP 1 LASTPIN (-2925 825) BN 0
J 2
(-2873 833);
DISPLAY 0.617021 (-2873 833);
PAINT GREEN (-2873 833);
FORCEPROP 2 LAST CDS_LIB mstr_standard
J 0
(-2875 825);
PAINT MONO (-2875 825);
DISPLAY INVISIBLE (-2875 825);
FORCEPROP 1 LAST BODY_TYPE PLUMBING
J 2
(-2875 775);
DISPLAY 1.595745 (-2875 775);
PAINT GREEN (-2875 775);
DISPLAY INVISIBLE (-2875 775);
FORCEPROP 1 LAST HDL_TAP TRUE
J 2
(-3200 700);
DISPLAY 1.595745 (-3200 700);
PAINT GREEN (-3200 700);
DISPLAY INVISIBLE (-3200 700);
FORCEPROP 1 LAST PATH I89
J 2
(-2873 825);
DISPLAY 0.872340 (-2873 825);
PAINT GREEN (-2873 825);
DISPLAY INVISIBLE (-2873 825);
FORCEADD TAP..6
(-5600 875);
FORCEPROP 3 LASTPIN (-5550 875) SIG_NAME M_H_CLK_DP<1>
J 0
(-5540 885);
DISPLAY 0.659574 (-5540 885);
PAINT MONO (-5540 885);
DISPLAY INVISIBLE (-5540 885);
FORCEPROP 1 LASTPIN (-5550 875) BN 1
J 0
(-5602 883);
DISPLAY 0.617021 (-5602 883);
PAINT GREEN (-5602 883);
FORCEPROP 2 LAST CDS_LIB mstr_standard
J 0
(-5600 875);
PAINT MONO (-5600 875);
DISPLAY INVISIBLE (-5600 875);
FORCEPROP 1 LAST BODY_TYPE PLUMBING
J 0
(-5600 825);
DISPLAY 1.595745 (-5600 825);
PAINT GREEN (-5600 825);
DISPLAY INVISIBLE (-5600 825);
FORCEPROP 1 LAST HDL_TAP TRUE
J 0
(-5275 750);
DISPLAY 1.595745 (-5275 750);
PAINT GREEN (-5275 750);
DISPLAY INVISIBLE (-5275 750);
FORCEPROP 1 LAST PATH I9
J 0
(-5602 875);
DISPLAY 0.872340 (-5602 875);
PAINT GREEN (-5602 875);
DISPLAY INVISIBLE (-5602 875);
FORCEADD TAP..6
R 2
(-2875 875);
FORCEPROP 3 LASTPIN (-2925 875) SIG_NAME M_H_BG<1>
J 0
(-2915 885);
DISPLAY 0.659574 (-2915 885);
PAINT MONO (-2915 885);
DISPLAY INVISIBLE (-2915 885);
FORCEPROP 1 LASTPIN (-2925 875) BN 1
J 2
(-2873 883);
DISPLAY 0.617021 (-2873 883);
PAINT GREEN (-2873 883);
FORCEPROP 2 LAST CDS_LIB mstr_standard
J 0
(-2875 875);
PAINT MONO (-2875 875);
DISPLAY INVISIBLE (-2875 875);
FORCEPROP 1 LAST BODY_TYPE PLUMBING
J 2
(-2875 825);
DISPLAY 1.595745 (-2875 825);
PAINT GREEN (-2875 825);
DISPLAY INVISIBLE (-2875 825);
FORCEPROP 1 LAST HDL_TAP TRUE
J 2
(-3200 750);
DISPLAY 1.595745 (-3200 750);
PAINT GREEN (-3200 750);
DISPLAY INVISIBLE (-3200 750);
FORCEPROP 1 LAST PATH I90
J 2
(-2873 875);
DISPLAY 0.872340 (-2873 875);
PAINT GREEN (-2873 875);
DISPLAY INVISIBLE (-2873 875);
FORCEADD TAP..6
R 2
(-2875 1075);
FORCEPROP 3 LASTPIN (-2925 1075) SIG_NAME M_H_CS_N<2>
J 0
(-2915 1085);
DISPLAY 0.659574 (-2915 1085);
PAINT MONO (-2915 1085);
DISPLAY INVISIBLE (-2915 1085);
FORCEPROP 1 LASTPIN (-2925 1075) BN 2
J 2
(-2873 1083);
DISPLAY 0.617021 (-2873 1083);
PAINT GREEN (-2873 1083);
FORCEPROP 2 LAST CDS_LIB mstr_standard
J 0
(-2875 1075);
PAINT MONO (-2875 1075);
DISPLAY INVISIBLE (-2875 1075);
FORCEPROP 1 LAST BODY_TYPE PLUMBING
J 2
(-2875 1025);
DISPLAY 1.595745 (-2875 1025);
PAINT GREEN (-2875 1025);
DISPLAY INVISIBLE (-2875 1025);
FORCEPROP 1 LAST HDL_TAP TRUE
J 2
(-3200 950);
DISPLAY 1.595745 (-3200 950);
PAINT GREEN (-3200 950);
DISPLAY INVISIBLE (-3200 950);
FORCEPROP 1 LAST PATH I91
J 2
(-2873 1075);
DISPLAY 0.872340 (-2873 1075);
PAINT GREEN (-2873 1075);
DISPLAY INVISIBLE (-2873 1075);
FORCEADD TAP..6
R 2
(-2875 1025);
FORCEPROP 3 LASTPIN (-2925 1025) SIG_NAME M_H_CS_N<1>
J 0
(-2915 1035);
DISPLAY 0.659574 (-2915 1035);
PAINT MONO (-2915 1035);
DISPLAY INVISIBLE (-2915 1035);
FORCEPROP 1 LASTPIN (-2925 1025) BN 1
J 2
(-2873 1033);
DISPLAY 0.617021 (-2873 1033);
PAINT GREEN (-2873 1033);
FORCEPROP 2 LAST CDS_LIB mstr_standard
J 0
(-2875 1025);
PAINT MONO (-2875 1025);
DISPLAY INVISIBLE (-2875 1025);
FORCEPROP 1 LAST BODY_TYPE PLUMBING
J 2
(-2875 975);
DISPLAY 1.595745 (-2875 975);
PAINT GREEN (-2875 975);
DISPLAY INVISIBLE (-2875 975);
FORCEPROP 1 LAST HDL_TAP TRUE
J 2
(-3200 900);
DISPLAY 1.595745 (-3200 900);
PAINT GREEN (-3200 900);
DISPLAY INVISIBLE (-3200 900);
FORCEPROP 1 LAST PATH I92
J 2
(-2873 1025);
DISPLAY 0.872340 (-2873 1025);
PAINT GREEN (-2873 1025);
DISPLAY INVISIBLE (-2873 1025);
FORCEADD TAP..6
R 2
(-2875 975);
FORCEPROP 3 LASTPIN (-2925 975) SIG_NAME M_H_CS_N<0>
J 0
(-2915 985);
DISPLAY 0.659574 (-2915 985);
PAINT MONO (-2915 985);
DISPLAY INVISIBLE (-2915 985);
FORCEPROP 1 LASTPIN (-2925 975) BN 0
J 2
(-2873 983);
DISPLAY 0.617021 (-2873 983);
PAINT GREEN (-2873 983);
FORCEPROP 2 LAST CDS_LIB mstr_standard
J 0
(-2875 975);
PAINT MONO (-2875 975);
DISPLAY INVISIBLE (-2875 975);
FORCEPROP 1 LAST BODY_TYPE PLUMBING
J 2
(-2875 925);
DISPLAY 1.595745 (-2875 925);
PAINT GREEN (-2875 925);
DISPLAY INVISIBLE (-2875 925);
FORCEPROP 1 LAST HDL_TAP TRUE
J 2
(-3200 850);
DISPLAY 1.595745 (-3200 850);
PAINT GREEN (-3200 850);
DISPLAY INVISIBLE (-3200 850);
FORCEPROP 1 LAST PATH I93
J 2
(-2873 975);
DISPLAY 0.872340 (-2873 975);
PAINT GREEN (-2873 975);
DISPLAY INVISIBLE (-2873 975);
FORCEADD TAP..6
R 2
(-2875 1175);
FORCEPROP 3 LASTPIN (-2925 1175) SIG_NAME M_H_CS_N<4>
J 0
(-2915 1185);
DISPLAY 0.659574 (-2915 1185);
PAINT MONO (-2915 1185);
DISPLAY INVISIBLE (-2915 1185);
FORCEPROP 1 LASTPIN (-2925 1175) BN 4
J 2
(-2873 1183);
DISPLAY 0.617021 (-2873 1183);
PAINT GREEN (-2873 1183);
FORCEPROP 2 LAST CDS_LIB mstr_standard
J 0
(-2875 1175);
PAINT MONO (-2875 1175);
DISPLAY INVISIBLE (-2875 1175);
FORCEPROP 1 LAST BODY_TYPE PLUMBING
J 2
(-2875 1125);
DISPLAY 1.595745 (-2875 1125);
PAINT GREEN (-2875 1125);
DISPLAY INVISIBLE (-2875 1125);
FORCEPROP 1 LAST HDL_TAP TRUE
J 2
(-3200 1050);
DISPLAY 1.595745 (-3200 1050);
PAINT GREEN (-3200 1050);
DISPLAY INVISIBLE (-3200 1050);
FORCEPROP 1 LAST PATH I94
J 2
(-2873 1175);
DISPLAY 0.872340 (-2873 1175);
PAINT GREEN (-2873 1175);
DISPLAY INVISIBLE (-2873 1175);
FORCEADD TAP..6
R 2
(-2875 1125);
FORCEPROP 3 LASTPIN (-2925 1125) SIG_NAME M_H_CS_N<3>
J 0
(-2915 1135);
DISPLAY 0.659574 (-2915 1135);
PAINT MONO (-2915 1135);
DISPLAY INVISIBLE (-2915 1135);
FORCEPROP 1 LASTPIN (-2925 1125) BN 3
J 2
(-2873 1133);
DISPLAY 0.617021 (-2873 1133);
PAINT GREEN (-2873 1133);
FORCEPROP 2 LAST CDS_LIB mstr_standard
J 0
(-2875 1125);
PAINT MONO (-2875 1125);
DISPLAY INVISIBLE (-2875 1125);
FORCEPROP 1 LAST BODY_TYPE PLUMBING
J 2
(-2875 1075);
DISPLAY 1.595745 (-2875 1075);
PAINT GREEN (-2875 1075);
DISPLAY INVISIBLE (-2875 1075);
FORCEPROP 1 LAST HDL_TAP TRUE
J 2
(-3200 1000);
DISPLAY 1.595745 (-3200 1000);
PAINT GREEN (-3200 1000);
DISPLAY INVISIBLE (-3200 1000);
FORCEPROP 1 LAST PATH I95
J 2
(-2873 1125);
DISPLAY 0.872340 (-2873 1125);
PAINT GREEN (-2873 1125);
DISPLAY INVISIBLE (-2873 1125);
FORCEADD TAP..6
R 2
(-2875 1225);
FORCEPROP 3 LASTPIN (-2925 1225) SIG_NAME M_H_CS_N<5>
J 0
(-2915 1235);
DISPLAY 0.659574 (-2915 1235);
PAINT MONO (-2915 1235);
DISPLAY INVISIBLE (-2915 1235);
FORCEPROP 1 LASTPIN (-2925 1225) BN 5
J 2
(-2873 1233);
DISPLAY 0.617021 (-2873 1233);
PAINT GREEN (-2873 1233);
FORCEPROP 2 LAST CDS_LIB mstr_standard
J 0
(-2875 1225);
PAINT MONO (-2875 1225);
DISPLAY INVISIBLE (-2875 1225);
FORCEPROP 1 LAST BODY_TYPE PLUMBING
J 2
(-2875 1175);
DISPLAY 1.595745 (-2875 1175);
PAINT GREEN (-2875 1175);
DISPLAY INVISIBLE (-2875 1175);
FORCEPROP 1 LAST HDL_TAP TRUE
J 2
(-3200 1100);
DISPLAY 1.595745 (-3200 1100);
PAINT GREEN (-3200 1100);
DISPLAY INVISIBLE (-3200 1100);
FORCEPROP 1 LAST PATH I96
J 2
(-2873 1225);
DISPLAY 0.872340 (-2873 1225);
PAINT GREEN (-2873 1225);
DISPLAY INVISIBLE (-2873 1225);
FORCEADD TAP..6
R 2
(-2875 1275);
FORCEPROP 3 LASTPIN (-2925 1275) SIG_NAME M_H_CS_N<6>
J 0
(-2915 1285);
DISPLAY 0.659574 (-2915 1285);
PAINT MONO (-2915 1285);
DISPLAY INVISIBLE (-2915 1285);
FORCEPROP 1 LASTPIN (-2925 1275) BN 6
J 2
(-2873 1283);
DISPLAY 0.617021 (-2873 1283);
PAINT GREEN (-2873 1283);
FORCEPROP 2 LAST CDS_LIB mstr_standard
J 0
(-2875 1275);
PAINT MONO (-2875 1275);
DISPLAY INVISIBLE (-2875 1275);
FORCEPROP 1 LAST BODY_TYPE PLUMBING
J 2
(-2875 1225);
DISPLAY 1.595745 (-2875 1225);
PAINT GREEN (-2875 1225);
DISPLAY INVISIBLE (-2875 1225);
FORCEPROP 1 LAST HDL_TAP TRUE
J 2
(-3200 1150);
DISPLAY 1.595745 (-3200 1150);
PAINT GREEN (-3200 1150);
DISPLAY INVISIBLE (-3200 1150);
FORCEPROP 1 LAST PATH I97
J 2
(-2873 1275);
DISPLAY 0.872340 (-2873 1275);
PAINT GREEN (-2873 1275);
DISPLAY INVISIBLE (-2873 1275);
FORCEADD TAP..6
R 2
(-2875 1325);
FORCEPROP 3 LASTPIN (-2925 1325) SIG_NAME M_H_CS_N<7>
J 0
(-2915 1335);
DISPLAY 0.659574 (-2915 1335);
PAINT MONO (-2915 1335);
DISPLAY INVISIBLE (-2915 1335);
FORCEPROP 1 LASTPIN (-2925 1325) BN 7
J 2
(-2873 1333);
DISPLAY 0.617021 (-2873 1333);
PAINT GREEN (-2873 1333);
FORCEPROP 2 LAST CDS_LIB mstr_standard
J 0
(-2875 1325);
PAINT MONO (-2875 1325);
DISPLAY INVISIBLE (-2875 1325);
FORCEPROP 1 LAST BODY_TYPE PLUMBING
J 2
(-2875 1275);
DISPLAY 1.595745 (-2875 1275);
PAINT GREEN (-2875 1275);
DISPLAY INVISIBLE (-2875 1275);
FORCEPROP 1 LAST HDL_TAP TRUE
J 2
(-3200 1200);
DISPLAY 1.595745 (-3200 1200);
PAINT GREEN (-3200 1200);
DISPLAY INVISIBLE (-3200 1200);
FORCEPROP 1 LAST PATH I98
J 2
(-2873 1325);
DISPLAY 0.872340 (-2873 1325);
PAINT GREEN (-2873 1325);
DISPLAY INVISIBLE (-2873 1325);
FORCEADD TAP..6
R 2
(-2875 1425);
FORCEPROP 3 LASTPIN (-2925 1425) SIG_NAME M_H_ODT<0>
J 0
(-2915 1435);
DISPLAY 0.659574 (-2915 1435);
PAINT MONO (-2915 1435);
DISPLAY INVISIBLE (-2915 1435);
FORCEPROP 1 LASTPIN (-2925 1425) BN 0
J 2
(-2873 1433);
DISPLAY 0.617021 (-2873 1433);
PAINT GREEN (-2873 1433);
FORCEPROP 2 LAST CDS_LIB mstr_standard
J 0
(-2875 1425);
PAINT MONO (-2875 1425);
DISPLAY INVISIBLE (-2875 1425);
FORCEPROP 1 LAST BODY_TYPE PLUMBING
J 2
(-2875 1375);
DISPLAY 1.595745 (-2875 1375);
PAINT GREEN (-2875 1375);
DISPLAY INVISIBLE (-2875 1375);
FORCEPROP 1 LAST HDL_TAP TRUE
J 2
(-3200 1300);
DISPLAY 1.595745 (-3200 1300);
PAINT GREEN (-3200 1300);
DISPLAY INVISIBLE (-3200 1300);
FORCEPROP 1 LAST PATH I99
J 2
(-2873 1425);
DISPLAY 0.872340 (-2873 1425);
PAINT GREEN (-2873 1425);
DISPLAY INVISIBLE (-2873 1425);
FORCEADD PRELIM..10
(-4240 2565);
PAINT GRAY (-4240 2565);
FORCEPROP 2 LAST CDS_LIB mstr_misc
J 0
(-4240 2565);
PAINT ORANGE (-4240 2565);
DISPLAY INVISIBLE (-4240 2565);
FORCEPROP 1 LAST COMMENT_BODY TRUE
J 0
(-4240 2565);
PAINT ORANGE (-4240 2565);
DISPLAY INVISIBLE (-4240 2565);
FORCEADD INTEL_CORP_BPAGE..1
(0 0);
FORCEPROP 1 LAST CDS_CON_LAST_MODIFIED Fri Jun 16 17:48:23 2017
J 0
(-1425 325);
DISPLAY 1.340426 (-1425 325);
PAINT GREEN (-1425 325);
DISPLAY INVISIBLE (-1425 325);
FORCEPROP 1 LAST CUSTOM_TXT_CDS <CURRENT_DESIGN_SHEET> OF <TOTAL_DESIGN_SHEETS>
J 0
(-500 25);
PAINT ORANGE (-500 25);
FORCEPROP 1 LAST CUSTOM_TXT_CDS <CON_LAST_MODIFIED>
J 0
(-4000 100);
PAINT ORANGE (-4000 100);
FORCEPROP 2 LAST CUSTOM_TXT_CDS <XR_PAGE_TITLE>
J 0
(-7890 5250);
DISPLAY 0.638298 (-7890 5250);
PAINT PINK (-7890 5250);
DISPLAY INVISIBLE (-7890 5250);
FORCEPROP 1 LAST SCH_TITLE SKYLAKE - SKT1 - 4 OF 21
J 0
(-7950 50);
DISPLAY 1.212766 (-7950 50);
PAINT GREEN (-7950 50);
FORCEPROP 2 LAST PAGE_BORDER TRUE
J 0
(-7890 5250);
DISPLAY 0.851064 (-7890 5250);
PAINT PINK (-7890 5250);
DISPLAY INVISIBLE (-7890 5250);
FORCEPROP 2 LAST CDS_LIB mstr_symbols
J 0
(0 0);
PAINT ORANGE (0 0);
DISPLAY INVISIBLE (0 0);
FORCEPROP 1 LAST COMMENT_BODY TRUE
J 0
(12 12);
DISPLAY 0.638298 (12 12);
PAINT GREEN (12 12);
DISPLAY INVISIBLE (12 12);
FORCEPROP 2 LAST CDS_XR_PAGE_TITLE CR-58 : @BASEBOARD_FAB2_LIB.BASEBOARD_FAB2(SCH_1):PAGE58
J 0
(-7890 5250);
DISPLAY 0.638298 (-7890 5250);
PAINT PINK (-7890 5250);
DISPLAY INVISIBLE (-7890 5250);
FORCEADD DESIGN_NOTE..1
(-6225 375);
FORCEPROP 0 LAST L1 CPU SYMBOLS 1-30 ARE PRELIMINARY AND SUBJECT TO CHANGE
J 0
(-6425 250);
DISPLAY 1.021277 (-6425 250);
PAINT ORANGE (-6425 250);
FORCEPROP 2 LAST CDS_LIB mstr_symbols
J 0
(-6225 375);
PAINT ORANGE (-6225 375);
DISPLAY INVISIBLE (-6225 375);
FORCEPROP 1 LAST COMMENT_BODY TRUE
J 0
(-6200 475);
DISPLAY 0.978723 (-6200 475);
PAINT ORANGE (-6200 475);
DISPLAY INVISIBLE (-6200 475);
WIRE 17 -1 (-2825 3850)(-2825 3900);
WIRE 17 -1 (-2825 3900)(-2825 3950);
WIRE 17 -1 (-2825 3950)(-2825 4000);
WIRE 17 -1 (-2825 4000)(-2825 4050);
WIRE 17 -1 (-2825 4050)(-2825 4100);
WIRE 17 -1 (-2825 4100)(-2825 4150);
WIRE 17 -1 (-2825 4150)(-2825 4200);
WIRE 17 -1 (-2825 4200)(-2825 4250);
WIRE 17 -1 (-2825 4250)(-2825 4300);
WIRE 17 -1 (-2825 4300)(-2825 4350);
WIRE 17 -1 (-2825 4350)(-2825 4400);
WIRE 17 -1 (-2825 4400)(-2825 4450);
WIRE 17 -1 (-2825 4450)(-2825 4500);
WIRE 17 -1 (-2825 4500)(-2825 4550);
WIRE 17 -1 (-2825 4550)(-2825 4600);
WIRE 17 -1 (-2825 4600)(-2825 4650);
WIRE 17 -1 (-2075 4750)(-2825 4750);
FORCEPROP 2 LAST SIG_NAME M_H_DQS_DP<17:0>
J 0
(-2725 4760);
DISPLAY 0.617021 (-2725 4760);
PAINT ORANGE (-2725 4760);
WIRE 17 -1 (-2825 4650)(-2825 4700);
WIRE 17 -1 (-2825 4700)(-2825 4750);
WIRE 17 -1 (-2825 2900)(-2825 2950);
WIRE 17 -1 (-2825 2950)(-2825 3000);
WIRE 17 -1 (-2825 3000)(-2825 3050);
WIRE 17 -1 (-2825 3050)(-2825 3100);
WIRE 17 -1 (-2825 3100)(-2825 3150);
WIRE 17 -1 (-2825 3150)(-2825 3200);
WIRE 17 -1 (-2825 3200)(-2825 3250);
WIRE 17 -1 (-2825 3250)(-2825 3300);
WIRE 17 -1 (-2825 3300)(-2825 3350);
WIRE 17 -1 (-2825 3350)(-2825 3400);
WIRE 17 -1 (-2825 3400)(-2825 3450);
WIRE 17 -1 (-2825 3450)(-2825 3500);
WIRE 17 -1 (-2825 3500)(-2825 3550);
WIRE 17 -1 (-2825 3550)(-2825 3600);
WIRE 17 -1 (-2825 3600)(-2825 3650);
WIRE 17 -1 (-2825 3650)(-2825 3700);
WIRE 17 -1 (-2075 3775)(-2825 3775);
FORCEPROP 2 LAST SIG_NAME M_H_DQS_DN<17:0>
J 0
(-2725 3785);
DISPLAY 0.617021 (-2725 3785);
PAINT ORANGE (-2725 3785);
WIRE 17 -1 (-2825 3700)(-2825 3750);
WIRE 17 -1 (-2825 3750)(-2825 3775);
WIRE 17 -1 (-2825 1950)(-2825 2000);
WIRE 17 -1 (-2825 2000)(-2825 2050);
WIRE 17 -1 (-2825 2050)(-2825 2100);
WIRE 17 -1 (-2825 2100)(-2825 2150);
WIRE 17 -1 (-2825 2150)(-2825 2200);
WIRE 17 -1 (-2825 2200)(-2825 2250);
WIRE 17 -1 (-2825 2250)(-2825 2300);
WIRE 17 -1 (-2825 2300)(-2825 2350);
WIRE 17 -1 (-2825 2350)(-2825 2400);
WIRE 17 -1 (-2825 2400)(-2825 2450);
WIRE 17 -1 (-2825 2450)(-2825 2500);
WIRE 17 -1 (-2825 2500)(-2825 2550);
WIRE 17 -1 (-2825 2550)(-2825 2600);
WIRE 17 -1 (-2825 2600)(-2825 2650);
WIRE 17 -1 (-2825 2650)(-2825 2700);
WIRE 17 -1 (-2825 2700)(-2825 2750);
WIRE 17 -1 (-2075 2825)(-2825 2825);
FORCEPROP 2 LAST SIG_NAME M_H_MA<17:0>
J 0
(-2725 2835);
DISPLAY 0.617021 (-2725 2835);
PAINT ORANGE (-2725 2835);
WIRE 17 -1 (-2825 2750)(-2825 2800);
WIRE 17 -1 (-2825 2800)(-2825 2825);
WIRE 17 -1 (-2075 825)(-2825 825);
FORCEPROP 2 LAST SIG_NAME M_H_BA<1:0>
J 0
(-2725 835);
DISPLAY 0.617021 (-2725 835);
PAINT ORANGE (-2725 835);
WIRE 17 -1 (-2825 750)(-2825 800);
WIRE 17 -1 (-2825 800)(-2825 825);
WIRE 17 -1 (-2075 925)(-2825 925);
FORCEPROP 2 LAST SIG_NAME M_H_BG<1:0>
J 0
(-2725 935);
DISPLAY 0.617021 (-2725 935);
PAINT ORANGE (-2725 935);
WIRE 17 -1 (-2825 850)(-2825 900);
WIRE 17 -1 (-2825 900)(-2825 925);
WIRE 17 -1 (-2825 1700)(-2825 1750);
WIRE 17 -1 (-2825 1750)(-2825 1800);
WIRE 17 -1 (-2075 1875)(-2825 1875);
FORCEPROP 2 LAST SIG_NAME M_H_CKE<3:0>
J 0
(-2725 1885);
DISPLAY 0.617021 (-2725 1885);
PAINT ORANGE (-2725 1885);
WIRE 17 -1 (-2825 1800)(-2825 1850);
WIRE 17 -1 (-2825 1850)(-2825 1875);
WIRE 17 -1 (-2825 1000)(-2825 1050);
WIRE 17 -1 (-2825 1050)(-2825 1100);
WIRE 17 -1 (-2825 1100)(-2825 1150);
WIRE 17 -1 (-2825 1150)(-2825 1200);
WIRE 17 -1 (-2825 1200)(-2825 1250);
WIRE 17 -1 (-2825 1250)(-2825 1300);
WIRE 17 -1 (-2075 1375)(-2825 1375);
FORCEPROP 2 LAST SIG_NAME M_H_CS_N<7:0>
J 0
(-2725 1385);
DISPLAY 0.617021 (-2725 1385);
PAINT ORANGE (-2725 1385);
WIRE 17 -1 (-2825 1300)(-2825 1350);
WIRE 17 -1 (-2825 1350)(-2825 1375);
WIRE 17 -1 (-2825 1450)(-2825 1500);
WIRE 17 -1 (-2825 1500)(-2825 1550);
WIRE 17 -1 (-2075 1625)(-2825 1625);
FORCEPROP 2 LAST SIG_NAME M_H_ODT<3:0>
J 0
(-2725 1635);
DISPLAY 0.617021 (-2725 1635);
PAINT ORANGE (-2725 1635);
WIRE 17 -1 (-2825 1550)(-2825 1600);
WIRE 17 -1 (-2825 1600)(-2825 1625);
WIRE 17 -1 (-5650 1550)(-5650 1600);
WIRE 17 -1 (-5650 1600)(-5650 1650);
WIRE 17 -1 (-5650 1650)(-5650 1700);
WIRE 17 -1 (-5650 1700)(-5650 1750);
WIRE 17 -1 (-5650 1750)(-5650 1800);
WIRE 17 -1 (-5650 1800)(-5650 1850);
WIRE 17 -1 (-5650 1850)(-5650 1900);
WIRE 17 -1 (-5650 1900)(-5650 1950);
WIRE 17 -1 (-5650 1950)(-5650 2000);
WIRE 17 -1 (-5650 2000)(-5650 2050);
WIRE 17 -1 (-5650 2050)(-5650 2100);
WIRE 17 -1 (-5650 2100)(-5650 2150);
WIRE 17 -1 (-5650 2150)(-5650 2200);
WIRE 17 -1 (-5650 2200)(-5650 2250);
WIRE 17 -1 (-5650 2250)(-5650 2300);
WIRE 17 -1 (-5650 2300)(-5650 2350);
WIRE 17 -1 (-5650 2350)(-5650 2400);
WIRE 17 -1 (-5650 2400)(-5650 2450);
WIRE 17 -1 (-5650 2450)(-5650 2500);
WIRE 17 -1 (-5650 2500)(-5650 2550);
WIRE 17 -1 (-5650 2550)(-5650 2600);
WIRE 17 -1 (-5650 2600)(-5650 2650);
WIRE 17 -1 (-5650 2650)(-5650 2700);
WIRE 17 -1 (-5650 2700)(-5650 2750);
WIRE 17 -1 (-5650 2750)(-5650 2800);
WIRE 17 -1 (-5650 2800)(-5650 2850);
WIRE 17 -1 (-5650 2850)(-5650 2900);
WIRE 17 -1 (-5650 2900)(-5650 2950);
WIRE 17 -1 (-5650 2950)(-5650 3000);
WIRE 17 -1 (-5650 3000)(-5650 3050);
WIRE 17 -1 (-5650 3050)(-5650 3100);
WIRE 17 -1 (-5650 3100)(-5650 3150);
WIRE 17 -1 (-5650 3150)(-5650 3200);
WIRE 17 -1 (-5650 3200)(-5650 3250);
WIRE 17 -1 (-5650 3250)(-5650 3300);
WIRE 17 -1 (-5650 3300)(-5650 3350);
WIRE 17 -1 (-5650 3350)(-5650 3400);
WIRE 17 -1 (-5650 3400)(-5650 3450);
WIRE 17 -1 (-5650 3450)(-5650 3500);
WIRE 17 -1 (-5650 3500)(-5650 3550);
WIRE 17 -1 (-5650 3550)(-5650 3600);
WIRE 17 -1 (-5650 3600)(-5650 3650);
WIRE 17 -1 (-5650 3650)(-5650 3700);
WIRE 17 -1 (-5650 3700)(-5650 3750);
WIRE 17 -1 (-5650 3750)(-5650 3800);
WIRE 17 -1 (-5650 3800)(-5650 3850);
WIRE 17 -1 (-5650 3850)(-5650 3900);
WIRE 17 -1 (-5650 3900)(-5650 3950);
WIRE 17 -1 (-5650 3950)(-5650 4000);
WIRE 17 -1 (-5650 4000)(-5650 4050);
WIRE 17 -1 (-5650 4050)(-5650 4100);
WIRE 17 -1 (-5650 4100)(-5650 4150);
WIRE 17 -1 (-5650 4150)(-5650 4200);
WIRE 17 -1 (-5650 4200)(-5650 4250);
WIRE 17 -1 (-5650 4250)(-5650 4300);
WIRE 17 -1 (-5650 4300)(-5650 4350);
WIRE 17 -1 (-5650 4350)(-5650 4400);
WIRE 17 -1 (-5650 4400)(-5650 4450);
WIRE 17 -1 (-5650 4450)(-5650 4500);
WIRE 17 -1 (-5650 4500)(-5650 4550);
WIRE 17 -1 (-5650 4550)(-5650 4600);
WIRE 17 -1 (-5650 4800)(-6400 4800);
FORCEPROP 2 LAST SIG_NAME M_H_DQ<63:0>
J 0
(-6350 4810);
DISPLAY 0.617021 (-6350 4810);
PAINT ORANGE (-6350 4810);
WIRE 17 -1 (-5650 4700)(-5650 4800);
WIRE 17 -1 (-5650 4600)(-5650 4650);
WIRE 17 -1 (-5650 4650)(-5650 4700);
WIRE 17 -1 (-5650 650)(-5650 700);
WIRE 17 -1 (-5650 700)(-5650 750);
WIRE 17 -1 (-5650 825)(-6400 825);
FORCEPROP 2 LAST SIG_NAME M_H_CLK_DN<3:0>
J 0
(-6350 835);
DISPLAY 0.617021 (-6350 835);
PAINT ORANGE (-6350 835);
WIRE 17 -1 (-5650 750)(-5650 800);
WIRE 17 -1 (-5650 800)(-5650 825);
WIRE 17 -1 (-5650 850)(-5650 900);
WIRE 17 -1 (-5650 900)(-5650 950);
WIRE 17 -1 (-5650 1025)(-6400 1025);
FORCEPROP 2 LAST SIG_NAME M_H_CLK_DP<3:0>
J 0
(-6350 1035);
DISPLAY 0.617021 (-6350 1035);
PAINT ORANGE (-6350 1035);
WIRE 17 -1 (-5650 950)(-5650 1000);
WIRE 17 -1 (-5650 1000)(-5650 1025);
WIRE 17 -1 (-5650 1100)(-5650 1150);
WIRE 17 -1 (-5650 1150)(-5650 1200);
WIRE 17 -1 (-5650 1200)(-5650 1250);
WIRE 17 -1 (-5650 1250)(-5650 1300);
WIRE 17 -1 (-5650 1300)(-5650 1350);
WIRE 17 -1 (-5650 1350)(-5650 1400);
WIRE 17 -1 (-5650 1475)(-6400 1475);
FORCEPROP 2 LAST SIG_NAME M_H_ECC<7:0>
J 0
(-6350 1485);
DISPLAY 0.617021 (-6350 1485);
PAINT ORANGE (-6350 1485);
WIRE 17 -1 (-5650 1400)(-5650 1450);
WIRE 17 -1 (-5650 1450)(-5650 1475);
WIRE 16 -1 (-5050 4275)(-5550 4275);
WIRE 16 -1 (-5550 3575)(-5050 3575);
WIRE 16 -1 (-5050 4125)(-5550 4125);
WIRE 16 -1 (-3350 1525)(-2925 1525);
WIRE 16 -1 (-5550 3225)(-5050 3225);
WIRE 16 -1 (-5550 3125)(-5050 3125);
WIRE 16 -1 (-5050 3375)(-5550 3375);
WIRE 16 -1 (-5050 525)(-6400 525);
FORCEPROP 2 LAST SIG_NAME M_H_C<2>
J 0
(-6350 535);
DISPLAY 0.617021 (-6350 535);
PAINT ORANGE (-6350 535);
WIRE 16 -1 (-5050 1075)(-5550 1075);
WIRE 16 -1 (-5050 1125)(-5550 1125);
WIRE 16 -1 (-5050 1175)(-5550 1175);
WIRE 16 -1 (-5050 1225)(-5550 1225);
WIRE 16 -1 (-5050 1275)(-5550 1275);
WIRE 16 -1 (-5050 1325)(-5550 1325);
WIRE 16 -1 (-5050 1375)(-5550 1375);
WIRE 16 -1 (-5050 1425)(-5550 1425);
WIRE 16 -1 (-5550 1525)(-5050 1525);
WIRE 16 -1 (-5550 1575)(-5050 1575);
WIRE 16 -1 (-5550 1625)(-5050 1625);
WIRE 16 -1 (-5050 1675)(-5550 1675);
WIRE 16 -1 (-5550 1725)(-5050 1725);
WIRE 16 -1 (-5550 1775)(-5050 1775);
WIRE 16 -1 (-5050 1825)(-5550 1825);
WIRE 16 -1 (-5550 1875)(-5050 1875);
WIRE 16 -1 (-5550 1925)(-5050 1925);
WIRE 16 -1 (-5550 1975)(-5050 1975);
WIRE 16 -1 (-5550 2025)(-5050 2025);
WIRE 16 -1 (-5050 825)(-5550 825);
WIRE 16 -1 (-5050 875)(-5550 875);
WIRE 16 -1 (-5050 925)(-5550 925);
WIRE 16 -1 (-5050 975)(-5550 975);
WIRE 16 -1 (-5050 625)(-5550 625);
WIRE 16 -1 (-5050 675)(-5550 675);
WIRE 16 -1 (-5050 725)(-5550 725);
WIRE 16 -1 (-5050 775)(-5550 775);
WIRE 16 -1 (-5550 2075)(-5050 2075);
WIRE 16 -1 (-5550 2125)(-5050 2125);
WIRE 16 -1 (-5550 2175)(-5050 2175);
WIRE 16 -1 (-5550 2225)(-5050 2225);
WIRE 16 -1 (-5050 2275)(-5550 2275);
WIRE 16 -1 (-5550 2325)(-5050 2325);
WIRE 16 -1 (-5550 2375)(-5050 2375);
WIRE 16 -1 (-5050 2425)(-5550 2425);
WIRE 16 -1 (-5550 2475)(-5050 2475);
WIRE 16 -1 (-5550 2525)(-5050 2525);
WIRE 16 -1 (-5550 2575)(-5050 2575);
WIRE 16 -1 (-5550 2625)(-5050 2625);
WIRE 16 -1 (-5050 2675)(-5550 2675);
WIRE 16 -1 (-5550 2725)(-5050 2725);
WIRE 16 -1 (-5550 2775)(-5050 2775);
WIRE 16 -1 (-5550 2825)(-5050 2825);
WIRE 16 -1 (-5550 2875)(-5050 2875);
WIRE 16 -1 (-5550 2925)(-5050 2925);
WIRE 16 -1 (-5550 2975)(-5050 2975);
WIRE 16 -1 (-5050 3025)(-5550 3025);
WIRE 16 -1 (-5550 3075)(-5050 3075);
WIRE 16 -1 (-5550 3175)(-5050 3175);
WIRE 16 -1 (-5550 3275)(-5050 3275);
WIRE 16 -1 (-5550 3325)(-5050 3325);
WIRE 16 -1 (-5550 3425)(-5050 3425);
WIRE 16 -1 (-5550 3475)(-5050 3475);
WIRE 16 -1 (-5050 3525)(-5550 3525);
WIRE 16 -1 (-5550 3625)(-5050 3625);
WIRE 16 -1 (-5050 3675)(-5550 3675);
WIRE 16 -1 (-5050 3725)(-5550 3725);
WIRE 16 -1 (-5050 3775)(-5550 3775);
WIRE 16 -1 (-5050 3825)(-5550 3825);
WIRE 16 -1 (-5050 3875)(-5550 3875);
WIRE 16 -1 (-5050 3925)(-5550 3925);
WIRE 16 -1 (-5050 3975)(-5550 3975);
WIRE 16 -1 (-5050 4025)(-5550 4025);
WIRE 16 -1 (-5050 4075)(-5550 4075);
WIRE 16 -1 (-5050 4175)(-5550 4175);
WIRE 16 -1 (-5050 4225)(-5550 4225);
WIRE 16 -1 (-5050 4325)(-5550 4325);
WIRE 16 -1 (-5050 4375)(-5550 4375);
WIRE 16 -1 (-5050 4425)(-5550 4425);
WIRE 16 -1 (-5050 4475)(-5550 4475);
WIRE 16 -1 (-5050 4525)(-5550 4525);
WIRE 16 -1 (-5050 4575)(-5550 4575);
WIRE 16 -1 (-5050 4625)(-5550 4625);
WIRE 16 -1 (-5050 4675)(-5550 4675);
WIRE 16 -1 (-3350 1425)(-2925 1425);
WIRE 16 -1 (-3350 1475)(-2925 1475);
WIRE 16 -1 (-3350 1575)(-2925 1575);
WIRE 16 -1 (-3350 1925)(-2925 1925);
WIRE 16 -1 (-3350 1975)(-2925 1975);
WIRE 16 -1 (-3350 2025)(-2925 2025);
WIRE 16 -1 (-3350 975)(-2925 975);
WIRE 16 -1 (-3350 1025)(-2925 1025);
WIRE 16 -1 (-3350 1075)(-2925 1075);
WIRE 16 -1 (-3350 1125)(-2925 1125);
WIRE 16 -1 (-3350 1175)(-2925 1175);
WIRE 16 -1 (-3350 1225)(-2925 1225);
WIRE 16 -1 (-3350 1275)(-2925 1275);
WIRE 16 -1 (-3350 1325)(-2925 1325);
WIRE 16 -1 (-3350 1675)(-2925 1675);
WIRE 16 -1 (-3350 1725)(-2925 1725);
WIRE 16 -1 (-3350 1775)(-2925 1775);
WIRE 16 -1 (-3350 1825)(-2925 1825);
WIRE 16 -1 (-3350 825)(-2925 825);
WIRE 16 -1 (-3350 875)(-2925 875);
WIRE 16 -1 (-3350 725)(-2925 725);
WIRE 16 -1 (-3350 775)(-2925 775);
WIRE 16 -1 (-3350 525)(-2075 525);
FORCEPROP 2 LAST SIG_NAME M_H_PAR
J 0
(-2725 535);
DISPLAY 0.617021 (-2725 535);
PAINT ORANGE (-2725 535);
WIRE 16 -1 (-3350 575)(-2075 575);
FORCEPROP 2 LAST SIG_NAME M_H_ALERT_N
J 0
(-2725 585);
DISPLAY 0.617021 (-2725 585);
PAINT ORANGE (-2725 585);
WIRE 16 -1 (-3350 625)(-2075 625);
FORCEPROP 2 LAST SIG_NAME M_H_ACT_N
J 0
(-2725 635);
DISPLAY 0.617021 (-2725 635);
PAINT ORANGE (-2725 635);
WIRE 16 -1 (-3350 2075)(-2925 2075);
WIRE 16 -1 (-3350 2125)(-2925 2125);
WIRE 16 -1 (-3350 2175)(-2925 2175);
WIRE 16 -1 (-3350 2225)(-2925 2225);
WIRE 16 -1 (-3350 2275)(-2925 2275);
WIRE 16 -1 (-3350 2325)(-2925 2325);
WIRE 16 -1 (-3350 2375)(-2925 2375);
WIRE 16 -1 (-3350 2425)(-2925 2425);
WIRE 16 -1 (-3350 2475)(-2925 2475);
WIRE 16 -1 (-3350 2525)(-2925 2525);
WIRE 16 -1 (-3350 2575)(-2925 2575);
WIRE 16 -1 (-3350 2625)(-2925 2625);
WIRE 16 -1 (-3350 2675)(-2925 2675);
WIRE 16 -1 (-3350 2725)(-2925 2725);
WIRE 16 -1 (-3350 2775)(-2925 2775);
WIRE 16 -1 (-3350 3825)(-2925 3825);
WIRE 16 -1 (-3350 3875)(-2925 3875);
WIRE 16 -1 (-3350 3925)(-2925 3925);
WIRE 16 -1 (-3350 3975)(-2925 3975);
WIRE 16 -1 (-3350 4025)(-2925 4025);
WIRE 16 -1 (-3350 4075)(-2925 4075);
WIRE 16 -1 (-3350 2875)(-2925 2875);
WIRE 16 -1 (-3350 2925)(-2925 2925);
WIRE 16 -1 (-3350 2975)(-2925 2975);
WIRE 16 -1 (-3350 3025)(-2925 3025);
WIRE 16 -1 (-3350 3075)(-2925 3075);
WIRE 16 -1 (-3350 3125)(-2925 3125);
WIRE 16 -1 (-3350 3175)(-2925 3175);
WIRE 16 -1 (-3350 3225)(-2925 3225);
WIRE 16 -1 (-3350 3275)(-2925 3275);
WIRE 16 -1 (-3350 3325)(-2925 3325);
WIRE 16 -1 (-3350 3375)(-2925 3375);
WIRE 16 -1 (-3350 3425)(-2925 3425);
WIRE 16 -1 (-3350 3475)(-2925 3475);
WIRE 16 -1 (-3350 3525)(-2925 3525);
WIRE 16 -1 (-3350 3575)(-2925 3575);
WIRE 16 -1 (-3350 3625)(-2925 3625);
WIRE 16 -1 (-3350 3675)(-2925 3675);
WIRE 16 -1 (-3350 3725)(-2925 3725);
WIRE 16 -1 (-3350 4125)(-2925 4125);
WIRE 16 -1 (-3350 4175)(-2925 4175);
WIRE 16 -1 (-3350 4225)(-2925 4225);
WIRE 16 -1 (-3350 4275)(-2925 4275);
WIRE 16 -1 (-3350 4325)(-2925 4325);
WIRE 16 -1 (-3350 4375)(-2925 4375);
WIRE 16 -1 (-3350 4425)(-2925 4425);
WIRE 16 -1 (-3350 4475)(-2925 4475);
WIRE 16 -1 (-3350 4525)(-2925 4525);
WIRE 16 -1 (-3350 4575)(-2925 4575);
WIRE 16 -1 (-3350 4625)(-2925 4625);
WIRE 16 -1 (-3350 4675)(-2925 4675);
FORCENOTE
ROOM=CPU1
(-7900 350) 0;
DISPLAY LEFT (-7900 350);
DISPLAY 1.723404 (-7900 350);
PAINT PURPLE (-7900 350);
FORCENOTE
BOM_COST=PROC_SOCKET
(-7900 225) 0;
DISPLAY LEFT (-7900 225);
DISPLAY 1.723404 (-7900 225);
PAINT PURPLE (-7900 225);
QUIT
